(kicad_sch
	(version 20250114)
	(generator "eeschema")
	(generator_version "9.0")
	(paper "A3")
	(title_block
		(title "Thunderbolt to 10GbE adapter")
		(date "2026-04-23")
		(rev "1.1.0")
	)
	(text "V_{OUT} = 0.6*(73.2k+10k)/10k = 4.992[V]"
		(exclude_from_sim no)
		(at 217.424 114.046 0)
		(effects
			(font
				(size 1.27 1.27)
			)
			(justify left bottom)
		)
	)
	(text "V_{OUT} = 0.6*(R_{FB_H}+R_{FB_L})/R_{FB_L}\n"
		(exclude_from_sim no)
		(at 217.424 111.506 0)
		(effects
			(font
				(size 1.27 1.27)
			)
			(justify left bottom)
		)
	)
	(text "5 V @ 6 A, expected 2 A consumption\n"
		(exclude_from_sim no)
		(at 226.06 119.38 0)
		(effects
			(font
				(size 1.27 1.27)
			)
			(justify left bottom)
		)
	)
	(text "Rail discharge"
		(exclude_from_sim no)
		(at 284.48 140.97 0)
		(effects
			(font
				(size 1.27 1.27)
			)
		)
	)
	(text "UVLO = 7 V"
		(exclude_from_sim no)
		(at 114.3 151.13 0)
		(effects
			(font
				(size 1.27 1.27)
			)
		)
	)
	(text "MODE1 = 200k GND -> SKIP + 750 kHz\nMODE2 = 100k GND -> 3ms SS + Ilim 54%"
		(exclude_from_sim no)
		(at 139.7 152.4 0)
		(effects
			(font
				(size 1.27 1.27)
			)
			(justify left)
		)
	)
	(text "Power arbiter"
		(exclude_from_sim no)
		(at 307.34 111.76 0)
		(effects
			(font
				(size 2.54 2.54)
				(thickness 0.4)
				(bold yes)
			)
			(justify left bottom)
		)
	)
	(text "9 V - 24 V\n10 W"
		(exclude_from_sim no)
		(at 54.61 127 0)
		(effects
			(font
				(size 1.27 1.27)
			)
			(justify left)
		)
	)
	(text "+5V DC/DC converter"
		(exclude_from_sim no)
		(at 166.624 108.458 0)
		(effects
			(font
				(size 2.54 2.54)
				(thickness 0.4)
				(bold yes)
			)
			(justify left bottom)
		)
	)
	(junction
		(at 288.29 121.92)
		(diameter 0)
		(color 0 0 0 0)
	)
	(junction
		(at 237.49 121.92)
		(diameter 0)
		(color 0 0 0 0)
	)
	(junction
		(at 337.82 167.64)
		(diameter 0)
		(color 0 0 0 0)
	)
	(junction
		(at 304.8 144.78)
		(diameter 0)
		(color 0 0 0 0)
	)
	(junction
		(at 340.36 121.92)
		(diameter 0)
		(color 0 0 0 0)
	)
	(junction
		(at 111.76 135.89)
		(diameter 0)
		(color 0 0 0 0)
	)
	(junction
		(at 80.01 116.84)
		(diameter 0)
		(color 0 0 0 0)
	)
	(junction
		(at 120.65 116.84)
		(diameter 0)
		(color 0 0 0 0)
	)
	(junction
		(at 331.47 121.92)
		(diameter 0)
		(color 0 0 0 0)
	)
	(junction
		(at 260.35 121.92)
		(diameter 0)
		(color 0 0 0 0)
	)
	(junction
		(at 337.82 121.92)
		(diameter 0)
		(color 0 0 0 0)
	)
	(junction
		(at 252.73 121.92)
		(diameter 0)
		(color 0 0 0 0)
	)
	(junction
		(at 227.33 129.54)
		(diameter 0)
		(color 0 0 0 0)
	)
	(junction
		(at 227.33 121.92)
		(diameter 0)
		(color 0 0 0 0)
	)
	(junction
		(at 304.8 121.92)
		(diameter 0)
		(color 0 0 0 0)
	)
	(junction
		(at 346.71 121.92)
		(diameter 0)
		(color 0 0 0 0)
	)
	(junction
		(at 346.71 167.64)
		(diameter 0)
		(color 0 0 0 0)
	)
	(junction
		(at 101.6 116.84)
		(diameter 0)
		(color 0 0 0 0)
	)
	(junction
		(at 158.75 132.08)
		(diameter 0)
		(color 0 0 0 0)
	)
	(junction
		(at 295.91 134.62)
		(diameter 0)
		(color 0 0 0 0)
	)
	(junction
		(at 224.79 121.92)
		(diameter 0)
		(color 0 0 0 0)
	)
	(junction
		(at 130.81 116.84)
		(diameter 0)
		(color 0 0 0 0)
	)
	(junction
		(at 295.91 121.92)
		(diameter 0)
		(color 0 0 0 0)
	)
	(junction
		(at 199.39 137.16)
		(diameter 0)
		(color 0 0 0 0)
	)
	(junction
		(at 87.63 116.84)
		(diameter 0)
		(color 0 0 0 0)
	)
	(junction
		(at 346.71 125.73)
		(diameter 0)
		(color 0 0 0 0)
	)
	(junction
		(at 245.11 121.92)
		(diameter 0)
		(color 0 0 0 0)
	)
	(junction
		(at 142.24 127)
		(diameter 0)
		(color 0 0 0 0)
	)
	(junction
		(at 110.49 116.84)
		(diameter 0)
		(color 0 0 0 0)
	)
	(junction
		(at 68.58 140.97)
		(diameter 0)
		(color 0 0 0 0)
	)
	(junction
		(at 270.51 121.92)
		(diameter 0)
		(color 0 0 0 0)
	)
	(junction
		(at 304.8 139.7)
		(diameter 0)
		(color 0 0 0 0)
	)
	(junction
		(at 101.6 135.89)
		(diameter 0)
		(color 0 0 0 0)
	)
	(junction
		(at 72.39 116.84)
		(diameter 0)
		(color 0 0 0 0)
	)
	(junction
		(at 68.58 121.92)
		(diameter 0)
		(color 0 0 0 0)
	)
	(no_connect
		(at 198.12 124.46)
	)
	(no_connect
		(at 325.12 139.7)
	)
	(no_connect
		(at 176.53 137.16)
	)
	(wire
		(pts
			(xy 101.6 135.89) (xy 101.6 137.16)
		)
		(stroke
			(width 0)
			(type default)
		)
	)
	(wire
		(pts
			(xy 331.47 204.47) (xy 331.47 203.2)
		)
		(stroke
			(width 0)
			(type default)
		)
	)
	(wire
		(pts
			(xy 323.85 176.53) (xy 327.66 176.53)
		)
		(stroke
			(width 0)
			(type default)
		)
	)
	(wire
		(pts
			(xy 101.6 116.84) (xy 110.49 116.84)
		)
		(stroke
			(width 0)
			(type default)
		)
	)
	(wire
		(pts
			(xy 87.63 116.84) (xy 101.6 116.84)
		)
		(stroke
			(width 0)
			(type default)
		)
	)
	(wire
		(pts
			(xy 68.58 119.38) (xy 67.31 119.38)
		)
		(stroke
			(width 0)
			(type default)
		)
	)
	(wire
		(pts
			(xy 101.6 134.62) (xy 101.6 135.89)
		)
		(stroke
			(width 0)
			(type default)
		)
	)
	(wire
		(pts
			(xy 111.76 135.89) (xy 111.76 137.16)
		)
		(stroke
			(width 0)
			(type default)
		)
	)
	(wire
		(pts
			(xy 337.82 167.64) (xy 346.71 167.64)
		)
		(stroke
			(width 0)
			(type default)
		)
	)
	(wire
		(pts
			(xy 198.12 116.84) (xy 209.55 116.84)
		)
		(stroke
			(width 0)
			(type default)
		)
	)
	(wire
		(pts
			(xy 130.81 123.19) (xy 130.81 124.46)
		)
		(stroke
			(width 0)
			(type default)
		)
	)
	(wire
		(pts
			(xy 142.24 119.38) (xy 142.24 120.65)
		)
		(stroke
			(width 0)
			(type default)
		)
	)
	(wire
		(pts
			(xy 167.64 134.62) (xy 176.53 134.62)
		)
		(stroke
			(width 0)
			(type default)
		)
	)
	(wire
		(pts
			(xy 304.8 137.16) (xy 307.34 137.16)
		)
		(stroke
			(width 0)
			(type default)
		)
	)
	(wire
		(pts
			(xy 199.39 137.16) (xy 199.39 134.62)
		)
		(stroke
			(width 0)
			(type default)
		)
	)
	(wire
		(pts
			(xy 270.51 129.54) (xy 270.51 130.81)
		)
		(stroke
			(width 0)
			(type default)
		)
	)
	(wire
		(pts
			(xy 198.12 119.38) (xy 214.63 119.38)
		)
		(stroke
			(width 0)
			(type default)
		)
	)
	(wire
		(pts
			(xy 353.06 134.62) (xy 353.06 135.89)
		)
		(stroke
			(width 0)
			(type default)
		)
	)
	(wire
		(pts
			(xy 142.24 119.38) (xy 153.67 119.38)
		)
		(stroke
			(width 0)
			(type default)
		)
	)
	(wire
		(pts
			(xy 158.75 140.97) (xy 158.75 142.24)
		)
		(stroke
			(width 0)
			(type default)
		)
	)
	(wire
		(pts
			(xy 337.82 121.92) (xy 340.36 121.92)
		)
		(stroke
			(width 0)
			(type default)
		)
	)
	(wire
		(pts
			(xy 331.47 195.58) (xy 332.74 195.58)
		)
		(stroke
			(width 0)
			(type default)
		)
	)
	(wire
		(pts
			(xy 330.2 167.64) (xy 337.82 167.64)
		)
		(stroke
			(width 0)
			(type default)
		)
	)
	(wire
		(pts
			(xy 325.12 198.12) (xy 332.74 198.12)
		)
		(stroke
			(width 0)
			(type default)
		)
	)
	(wire
		(pts
			(xy 68.58 121.92) (xy 68.58 140.97)
		)
		(stroke
			(width 0)
			(type default)
		)
	)
	(wire
		(pts
			(xy 309.88 167.64) (xy 320.04 167.64)
		)
		(stroke
			(width 0)
			(type default)
		)
	)
	(wire
		(pts
			(xy 331.47 121.92) (xy 331.47 134.62)
		)
		(stroke
			(width 0)
			(type default)
		)
	)
	(wire
		(pts
			(xy 325.12 137.16) (xy 327.66 137.16)
		)
		(stroke
			(width 0)
			(type default)
		)
	)
	(wire
		(pts
			(xy 142.24 127) (xy 176.53 127)
		)
		(stroke
			(width 0)
			(type default)
		)
	)
	(wire
		(pts
			(xy 337.82 121.92) (xy 337.82 123.19)
		)
		(stroke
			(width 0)
			(type default)
		)
	)
	(wire
		(pts
			(xy 330.2 121.92) (xy 331.47 121.92)
		)
		(stroke
			(width 0)
			(type default)
		)
	)
	(wire
		(pts
			(xy 67.31 116.84) (xy 72.39 116.84)
		)
		(stroke
			(width 0)
			(type default)
		)
	)
	(wire
		(pts
			(xy 288.29 121.92) (xy 288.29 127)
		)
		(stroke
			(width 0)
			(type default)
		)
	)
	(wire
		(pts
			(xy 68.58 140.97) (xy 68.58 151.13)
		)
		(stroke
			(width 0)
			(type default)
		)
	)
	(wire
		(pts
			(xy 120.65 116.84) (xy 120.65 118.11)
		)
		(stroke
			(width 0)
			(type default)
		)
	)
	(wire
		(pts
			(xy 270.51 121.92) (xy 279.4 121.92)
		)
		(stroke
			(width 0)
			(type default)
		)
	)
	(wire
		(pts
			(xy 101.6 116.84) (xy 101.6 129.54)
		)
		(stroke
			(width 0)
			(type default)
		)
	)
	(wire
		(pts
			(xy 167.64 134.62) (xy 167.64 135.89)
		)
		(stroke
			(width 0)
			(type default)
		)
	)
	(wire
		(pts
			(xy 68.58 119.38) (xy 68.58 121.92)
		)
		(stroke
			(width 0)
			(type default)
		)
	)
	(wire
		(pts
			(xy 304.8 120.65) (xy 304.8 121.92)
		)
		(stroke
			(width 0)
			(type default)
		)
	)
	(wire
		(pts
			(xy 270.51 121.92) (xy 270.51 124.46)
		)
		(stroke
			(width 0)
			(type default)
		)
	)
	(wire
		(pts
			(xy 295.91 142.24) (xy 295.91 144.78)
		)
		(stroke
			(width 0)
			(type default)
		)
	)
	(wire
		(pts
			(xy 309.88 167.64) (xy 309.88 166.37)
		)
		(stroke
			(width 0)
			(type default)
		)
	)
	(wire
		(pts
			(xy 158.75 135.89) (xy 158.75 132.08)
		)
		(stroke
			(width 0)
			(type default)
		)
	)
	(wire
		(pts
			(xy 149.86 140.97) (xy 149.86 142.24)
		)
		(stroke
			(width 0)
			(type default)
		)
	)
	(wire
		(pts
			(xy 120.65 124.46) (xy 120.65 123.19)
		)
		(stroke
			(width 0)
			(type default)
		)
	)
	(wire
		(pts
			(xy 72.39 116.84) (xy 80.01 116.84)
		)
		(stroke
			(width 0)
			(type default)
		)
	)
	(wire
		(pts
			(xy 295.91 144.78) (xy 304.8 144.78)
		)
		(stroke
			(width 0)
			(type default)
		)
	)
	(wire
		(pts
			(xy 142.24 135.89) (xy 142.24 127)
		)
		(stroke
			(width 0)
			(type default)
		)
	)
	(wire
		(pts
			(xy 346.71 125.73) (xy 346.71 167.64)
		)
		(stroke
			(width 0)
			(type default)
		)
	)
	(wire
		(pts
			(xy 80.01 128.27) (xy 80.01 134.62)
		)
		(stroke
			(width 0)
			(type default)
		)
	)
	(wire
		(pts
			(xy 149.86 129.54) (xy 149.86 135.89)
		)
		(stroke
			(width 0)
			(type default)
		)
	)
	(wire
		(pts
			(xy 227.33 135.89) (xy 227.33 139.7)
		)
		(stroke
			(width 0)
			(type default)
		)
	)
	(wire
		(pts
			(xy 346.71 167.64) (xy 346.71 168.91)
		)
		(stroke
			(width 0)
			(type default)
		)
	)
	(wire
		(pts
			(xy 111.76 135.89) (xy 123.19 135.89)
		)
		(stroke
			(width 0)
			(type default)
		)
	)
	(wire
		(pts
			(xy 64.77 140.97) (xy 68.58 140.97)
		)
		(stroke
			(width 0)
			(type default)
		)
	)
	(wire
		(pts
			(xy 80.01 116.84) (xy 87.63 116.84)
		)
		(stroke
			(width 0)
			(type default)
		)
	)
	(wire
		(pts
			(xy 245.11 129.54) (xy 245.11 130.81)
		)
		(stroke
			(width 0)
			(type default)
		)
	)
	(wire
		(pts
			(xy 130.81 116.84) (xy 130.81 118.11)
		)
		(stroke
			(width 0)
			(type default)
		)
	)
	(wire
		(pts
			(xy 227.33 121.92) (xy 227.33 123.19)
		)
		(stroke
			(width 0)
			(type default)
		)
	)
	(wire
		(pts
			(xy 130.81 116.84) (xy 176.53 116.84)
		)
		(stroke
			(width 0)
			(type default)
		)
	)
	(wire
		(pts
			(xy 110.49 116.84) (xy 110.49 118.11)
		)
		(stroke
			(width 0)
			(type default)
		)
	)
	(wire
		(pts
			(xy 353.06 140.97) (xy 353.06 142.24)
		)
		(stroke
			(width 0)
			(type default)
		)
	)
	(wire
		(pts
			(xy 284.48 121.92) (xy 288.29 121.92)
		)
		(stroke
			(width 0)
			(type default)
		)
	)
	(wire
		(pts
			(xy 149.86 129.54) (xy 176.53 129.54)
		)
		(stroke
			(width 0)
			(type default)
		)
	)
	(wire
		(pts
			(xy 346.71 167.64) (xy 363.22 167.64)
		)
		(stroke
			(width 0)
			(type default)
		)
	)
	(wire
		(pts
			(xy 295.91 134.62) (xy 307.34 134.62)
		)
		(stroke
			(width 0)
			(type default)
		)
	)
	(wire
		(pts
			(xy 260.35 121.92) (xy 270.51 121.92)
		)
		(stroke
			(width 0)
			(type default)
		)
	)
	(wire
		(pts
			(xy 224.79 121.92) (xy 227.33 121.92)
		)
		(stroke
			(width 0)
			(type default)
		)
	)
	(wire
		(pts
			(xy 142.24 125.73) (xy 142.24 127)
		)
		(stroke
			(width 0)
			(type default)
		)
	)
	(wire
		(pts
			(xy 214.63 116.84) (xy 214.63 119.38)
		)
		(stroke
			(width 0)
			(type default)
		)
	)
	(wire
		(pts
			(xy 198.12 137.16) (xy 199.39 137.16)
		)
		(stroke
			(width 0)
			(type default)
		)
	)
	(wire
		(pts
			(xy 288.29 132.08) (xy 288.29 134.62)
		)
		(stroke
			(width 0)
			(type default)
		)
	)
	(wire
		(pts
			(xy 304.8 121.92) (xy 320.04 121.92)
		)
		(stroke
			(width 0)
			(type default)
		)
	)
	(wire
		(pts
			(xy 346.71 125.73) (xy 353.06 125.73)
		)
		(stroke
			(width 0)
			(type default)
		)
	)
	(wire
		(pts
			(xy 153.67 119.38) (xy 153.67 132.08)
		)
		(stroke
			(width 0)
			(type default)
		)
	)
	(wire
		(pts
			(xy 120.65 116.84) (xy 130.81 116.84)
		)
		(stroke
			(width 0)
			(type default)
		)
	)
	(wire
		(pts
			(xy 227.33 130.81) (xy 227.33 129.54)
		)
		(stroke
			(width 0)
			(type default)
		)
	)
	(wire
		(pts
			(xy 295.91 121.92) (xy 295.91 134.62)
		)
		(stroke
			(width 0)
			(type default)
		)
	)
	(wire
		(pts
			(xy 199.39 139.7) (xy 199.39 137.16)
		)
		(stroke
			(width 0)
			(type default)
		)
	)
	(wire
		(pts
			(xy 288.29 121.92) (xy 295.91 121.92)
		)
		(stroke
			(width 0)
			(type default)
		)
	)
	(wire
		(pts
			(xy 270.51 135.89) (xy 270.51 137.16)
		)
		(stroke
			(width 0)
			(type default)
		)
	)
	(wire
		(pts
			(xy 198.12 121.92) (xy 218.44 121.92)
		)
		(stroke
			(width 0)
			(type default)
		)
	)
	(wire
		(pts
			(xy 223.52 121.92) (xy 224.79 121.92)
		)
		(stroke
			(width 0)
			(type default)
		)
	)
	(wire
		(pts
			(xy 87.63 115.57) (xy 87.63 116.84)
		)
		(stroke
			(width 0)
			(type default)
		)
	)
	(wire
		(pts
			(xy 198.12 129.54) (xy 227.33 129.54)
		)
		(stroke
			(width 0)
			(type default)
		)
	)
	(wire
		(pts
			(xy 304.8 139.7) (xy 304.8 144.78)
		)
		(stroke
			(width 0)
			(type default)
		)
	)
	(wire
		(pts
			(xy 260.35 121.92) (xy 260.35 124.46)
		)
		(stroke
			(width 0)
			(type default)
		)
	)
	(wire
		(pts
			(xy 245.11 121.92) (xy 245.11 124.46)
		)
		(stroke
			(width 0)
			(type default)
		)
	)
	(wire
		(pts
			(xy 167.64 140.97) (xy 167.64 142.24)
		)
		(stroke
			(width 0)
			(type default)
		)
	)
	(wire
		(pts
			(xy 304.8 137.16) (xy 304.8 139.7)
		)
		(stroke
			(width 0)
			(type default)
		)
	)
	(wire
		(pts
			(xy 331.47 121.92) (xy 337.82 121.92)
		)
		(stroke
			(width 0)
			(type default)
		)
	)
	(wire
		(pts
			(xy 252.73 121.92) (xy 252.73 124.46)
		)
		(stroke
			(width 0)
			(type default)
		)
	)
	(wire
		(pts
			(xy 337.82 173.99) (xy 337.82 175.26)
		)
		(stroke
			(width 0)
			(type default)
		)
	)
	(wire
		(pts
			(xy 327.66 128.27) (xy 327.66 137.16)
		)
		(stroke
			(width 0)
			(type default)
		)
	)
	(wire
		(pts
			(xy 224.79 127) (xy 224.79 121.92)
		)
		(stroke
			(width 0)
			(type default)
		)
	)
	(wire
		(pts
			(xy 237.49 121.92) (xy 237.49 124.46)
		)
		(stroke
			(width 0)
			(type default)
		)
	)
	(wire
		(pts
			(xy 110.49 124.46) (xy 110.49 123.19)
		)
		(stroke
			(width 0)
			(type default)
		)
	)
	(wire
		(pts
			(xy 80.01 116.84) (xy 80.01 123.19)
		)
		(stroke
			(width 0)
			(type default)
		)
	)
	(wire
		(pts
			(xy 64.77 138.43) (xy 72.39 138.43)
		)
		(stroke
			(width 0)
			(type default)
		)
	)
	(wire
		(pts
			(xy 142.24 140.97) (xy 142.24 142.24)
		)
		(stroke
			(width 0)
			(type default)
		)
	)
	(wire
		(pts
			(xy 337.82 167.64) (xy 337.82 168.91)
		)
		(stroke
			(width 0)
			(type default)
		)
	)
	(wire
		(pts
			(xy 101.6 135.89) (xy 111.76 135.89)
		)
		(stroke
			(width 0)
			(type default)
		)
	)
	(wire
		(pts
			(xy 111.76 142.24) (xy 111.76 143.51)
		)
		(stroke
			(width 0)
			(type default)
		)
	)
	(wire
		(pts
			(xy 158.75 132.08) (xy 176.53 132.08)
		)
		(stroke
			(width 0)
			(type default)
		)
	)
	(wire
		(pts
			(xy 325.12 134.62) (xy 331.47 134.62)
		)
		(stroke
			(width 0)
			(type default)
		)
	)
	(wire
		(pts
			(xy 306.07 176.53) (xy 318.77 176.53)
		)
		(stroke
			(width 0)
			(type default)
		)
	)
	(wire
		(pts
			(xy 353.06 125.73) (xy 353.06 129.54)
		)
		(stroke
			(width 0)
			(type default)
		)
	)
	(wire
		(pts
			(xy 363.22 167.64) (xy 363.22 170.18)
		)
		(stroke
			(width 0)
			(type default)
		)
	)
	(wire
		(pts
			(xy 101.6 142.24) (xy 101.6 143.51)
		)
		(stroke
			(width 0)
			(type default)
		)
	)
	(wire
		(pts
			(xy 165.1 124.46) (xy 176.53 124.46)
		)
		(stroke
			(width 0)
			(type default)
		)
	)
	(wire
		(pts
			(xy 237.49 121.92) (xy 245.11 121.92)
		)
		(stroke
			(width 0)
			(type default)
		)
	)
	(wire
		(pts
			(xy 245.11 121.92) (xy 252.73 121.92)
		)
		(stroke
			(width 0)
			(type default)
		)
	)
	(wire
		(pts
			(xy 72.39 138.43) (xy 72.39 116.84)
		)
		(stroke
			(width 0)
			(type default)
		)
	)
	(wire
		(pts
			(xy 325.12 194.31) (xy 325.12 198.12)
		)
		(stroke
			(width 0)
			(type default)
		)
	)
	(wire
		(pts
			(xy 295.91 121.92) (xy 304.8 121.92)
		)
		(stroke
			(width 0)
			(type default)
		)
	)
	(wire
		(pts
			(xy 110.49 116.84) (xy 120.65 116.84)
		)
		(stroke
			(width 0)
			(type default)
		)
	)
	(wire
		(pts
			(xy 331.47 194.31) (xy 331.47 195.58)
		)
		(stroke
			(width 0)
			(type default)
		)
	)
	(wire
		(pts
			(xy 337.82 128.27) (xy 337.82 129.54)
		)
		(stroke
			(width 0)
			(type default)
		)
	)
	(wire
		(pts
			(xy 252.73 129.54) (xy 252.73 130.81)
		)
		(stroke
			(width 0)
			(type default)
		)
	)
	(wire
		(pts
			(xy 198.12 134.62) (xy 199.39 134.62)
		)
		(stroke
			(width 0)
			(type default)
		)
	)
	(wire
		(pts
			(xy 304.8 139.7) (xy 307.34 139.7)
		)
		(stroke
			(width 0)
			(type default)
		)
	)
	(wire
		(pts
			(xy 68.58 121.92) (xy 67.31 121.92)
		)
		(stroke
			(width 0)
			(type default)
		)
	)
	(wire
		(pts
			(xy 304.8 144.78) (xy 304.8 147.32)
		)
		(stroke
			(width 0)
			(type default)
		)
	)
	(wire
		(pts
			(xy 252.73 121.92) (xy 260.35 121.92)
		)
		(stroke
			(width 0)
			(type default)
		)
	)
	(wire
		(pts
			(xy 346.71 121.92) (xy 346.71 125.73)
		)
		(stroke
			(width 0)
			(type default)
		)
	)
	(wire
		(pts
			(xy 346.71 173.99) (xy 346.71 175.26)
		)
		(stroke
			(width 0)
			(type default)
		)
	)
	(wire
		(pts
			(xy 237.49 129.54) (xy 237.49 130.81)
		)
		(stroke
			(width 0)
			(type default)
		)
	)
	(wire
		(pts
			(xy 363.22 175.26) (xy 363.22 176.53)
		)
		(stroke
			(width 0)
			(type default)
		)
	)
	(wire
		(pts
			(xy 227.33 121.92) (xy 237.49 121.92)
		)
		(stroke
			(width 0)
			(type default)
		)
	)
	(wire
		(pts
			(xy 340.36 120.65) (xy 340.36 121.92)
		)
		(stroke
			(width 0)
			(type default)
		)
	)
	(wire
		(pts
			(xy 331.47 203.2) (xy 332.74 203.2)
		)
		(stroke
			(width 0)
			(type default)
		)
	)
	(wire
		(pts
			(xy 321.31 200.66) (xy 332.74 200.66)
		)
		(stroke
			(width 0)
			(type default)
		)
	)
	(wire
		(pts
			(xy 295.91 134.62) (xy 295.91 137.16)
		)
		(stroke
			(width 0)
			(type default)
		)
	)
	(wire
		(pts
			(xy 153.67 132.08) (xy 158.75 132.08)
		)
		(stroke
			(width 0)
			(type default)
		)
	)
	(wire
		(pts
			(xy 260.35 129.54) (xy 260.35 130.81)
		)
		(stroke
			(width 0)
			(type default)
		)
	)
	(wire
		(pts
			(xy 227.33 128.27) (xy 227.33 129.54)
		)
		(stroke
			(width 0)
			(type default)
		)
	)
	(wire
		(pts
			(xy 340.36 121.92) (xy 346.71 121.92)
		)
		(stroke
			(width 0)
			(type default)
		)
	)
	(wire
		(pts
			(xy 327.66 173.99) (xy 327.66 176.53)
		)
		(stroke
			(width 0)
			(type default)
		)
	)
	(wire
		(pts
			(xy 198.12 127) (xy 224.79 127)
		)
		(stroke
			(width 0)
			(type default)
		)
	)
	(wire
		(pts
			(xy 346.71 119.38) (xy 346.71 121.92)
		)
		(stroke
			(width 0)
			(type default)
		)
	)
	(label "5V_VDRV"
		(at 175.26 134.62 180)
		(effects
			(font
				(size 1.27 1.27)
			)
			(justify right bottom)
		)
	)
	(label "5V_JACK"
		(at 306.07 176.53 0)
		(effects
			(font
				(size 1.27 1.27)
			)
			(justify left bottom)
		)
	)
	(label "5V_JACK"
		(at 321.31 200.66 0)
		(effects
			(font
				(size 1.27 1.27)
			)
			(justify left bottom)
		)
	)
	(label "5V_MODE1"
		(at 175.26 127 180)
		(effects
			(font
				(size 1.27 1.27)
			)
			(justify right bottom)
		)
	)
	(label "5V_EN"
		(at 123.19 135.89 180)
		(effects
			(font
				(size 1.27 1.27)
			)
			(justify right bottom)
		)
	)
	(label "5V_MODE2"
		(at 175.26 129.54 180)
		(effects
			(font
				(size 1.27 1.27)
			)
			(justify right bottom)
		)
	)
	(label "5V_BOOT"
		(at 198.12 116.84 0)
		(effects
			(font
				(size 1.27 1.27)
			)
			(justify left bottom)
		)
	)
	(label "5V_EN"
		(at 165.1 124.46 0)
		(effects
			(font
				(size 1.27 1.27)
			)
			(justify left bottom)
		)
	)
	(label "5V_FB"
		(at 199.39 129.54 0)
		(effects
			(font
				(size 1.27 1.27)
			)
			(justify left bottom)
		)
	)
	(label "5V_JACK"
		(at 288.29 121.92 0)
		(effects
			(font
				(size 1.27 1.27)
			)
			(justify left bottom)
		)
	)
	(label "5V_VDD"
		(at 175.26 132.08 180)
		(effects
			(font
				(size 1.27 1.27)
			)
			(justify right bottom)
		)
	)
	(label "5V_PHASE"
		(at 198.12 119.38 0)
		(effects
			(font
				(size 1.27 1.27)
			)
			(justify left bottom)
		)
	)
	(label "5V_OUT"
		(at 228.6 121.92 0)
		(effects
			(font
				(size 1.27 1.27)
			)
			(justify left bottom)
		)
	)
	(label "5V_SW"
		(at 198.12 121.92 0)
		(effects
			(font
				(size 1.27 1.27)
			)
			(justify left bottom)
		)
	)
	(symbol
		(lib_id "antmicroCapacitorsmisc:C_22u_25V_0805")
		(at 260.35 129.54 90)
		(unit 1)
		(exclude_from_sim no)
		(in_bom yes)
		(on_board yes)
		(dnp no)
		(property "Reference" "C321"
			(at 262.128 124.4601 90)
			(effects
				(font
					(size 1.27 1.27)
					(thickness 0.15)
				)
				(justify right)
			)
		)
		(property "Value" "C_22u_25V_0805"
			(at 270.51 109.22 0)
			(effects
				(font
					(size 1.27 1.27)
					(thickness 0.15)
				)
				(justify left bottom)
				(hide yes)
			)
		)
		(property "Footprint" "antmicro-footprints:C_0805_2012Metric"
			(at 273.05 109.22 0)
			(effects
				(font
					(size 1.27 1.27)
					(thickness 0.15)
				)
				(justify left bottom)
				(hide yes)
			)
		)
		(property "Datasheet" "https://product.samsungsem.com/mlcc/CL21A226MAYNNN.do"
			(at 275.59 109.22 0)
			(effects
				(font
					(size 1.27 1.27)
					(thickness 0.15)
				)
				(justify left bottom)
				(hide yes)
			)
		)
		(property "Description" "SMT Multilayer Ceramic Capacitor, 22uF, +/-20%, 25V, X5R, 0805 [2012 Metric]"
			(at 293.37 109.22 0)
			(effects
				(font
					(size 1.27 1.27)
				)
				(justify left bottom)
				(hide yes)
			)
		)
		(property "MPN" "CL21A226MAYNNNE"
			(at 278.13 109.22 0)
			(effects
				(font
					(size 1.27 1.27)
					(thickness 0.15)
				)
				(justify left bottom)
				(hide yes)
			)
		)
		(property "Manufacturer" "Samsung Electro-Mechanics"
			(at 280.67 109.22 0)
			(effects
				(font
					(size 1.27 1.27)
					(thickness 0.15)
				)
				(justify left bottom)
				(hide yes)
			)
		)
		(property "License" "Apache-2.0"
			(at 283.21 109.22 0)
			(effects
				(font
					(size 1.27 1.27)
					(thickness 0.15)
				)
				(justify left bottom)
				(hide yes)
			)
		)
		(property "Author" "Antmicro"
			(at 285.75 109.22 0)
			(effects
				(font
					(size 1.27 1.27)
					(thickness 0.15)
				)
				(justify left bottom)
				(hide yes)
			)
		)
		(property "Val" "22u"
			(at 262.128 127.0001 90)
			(effects
				(font
					(size 1.27 1.27)
					(thickness 0.15)
				)
				(justify right)
			)
		)
		(property "Voltage" "25V"
			(at 262.128 129.54 90)
			(effects
				(font
					(size 1.27 1.27)
				)
				(justify right)
			)
		)
		(property "Dielectric" "X5R"
			(at 290.83 109.22 0)
			(effects
				(font
					(size 1.27 1.27)
				)
				(justify left bottom)
				(hide yes)
			)
		)
		(property "Public" "False"
			(at 293.37 109.22 0)
			(effects
				(font
					(size 1.27 1.27)
				)
				(justify left bottom)
				(hide yes)
			)
		)
		(pin "2"
		)
		(pin "1"
		)
		(instances
			(project "thunderbolt-to-10gbe-adapter"
				(path ""
					(reference "C321")
					(unit 1)
				)
			)
		)
	)
	(symbol
		(lib_id "antmicroCapacitors0402:C_1u_0402")
		(at 158.75 140.97 90)
		(unit 1)
		(exclude_from_sim no)
		(in_bom yes)
		(on_board yes)
		(dnp no)
		(property "Reference" "C315"
			(at 159.385 136.525 90)
			(effects
				(font
					(size 1.27 1.27)
				)
				(justify right)
			)
		)
		(property "Value" "C_1u_0402"
			(at 168.91 120.65 0)
			(effects
				(font
					(size 1.27 1.27)
					(thickness 0.15)
				)
				(justify left bottom)
				(hide yes)
			)
		)
		(property "Footprint" "antmicro-footprints:C_0402_1005Metric"
			(at 171.45 120.65 0)
			(effects
				(font
					(size 1.27 1.27)
					(thickness 0.15)
				)
				(justify left bottom)
				(hide yes)
			)
		)
		(property "Datasheet" "https://product.tdk.com/en/search/capacitor/ceramic/mlcc/info?part_no=C1005X6S1A105K050BC"
			(at 173.99 120.65 0)
			(effects
				(font
					(size 1.27 1.27)
					(thickness 0.15)
				)
				(justify left bottom)
				(hide yes)
			)
		)
		(property "Description" "SMD Multilayer Ceramic Capacitor, 1 µF, 10 V, 0402 [1005 Metric], ± 10%, X6S, C"
			(at 158.75 140.97 0)
			(effects
				(font
					(size 1.27 1.27)
				)
				(hide yes)
			)
		)
		(property "Manufacturer" "TDK"
			(at 179.07 120.65 0)
			(effects
				(font
					(size 1.27 1.27)
					(thickness 0.15)
				)
				(justify left bottom)
				(hide yes)
			)
		)
		(property "MPN" "C1005X6S1A105K050BC"
			(at 176.53 120.65 0)
			(effects
				(font
					(size 1.27 1.27)
					(thickness 0.15)
				)
				(justify left bottom)
				(hide yes)
			)
		)
		(property "Val" "1u"
			(at 159.385 140.335 90)
			(effects
				(font
					(size 1.27 1.27)
					(thickness 0.15)
				)
				(justify right)
			)
		)
		(property "License" "Apache-2.0"
			(at 181.61 120.65 0)
			(effects
				(font
					(size 1.27 1.27)
					(thickness 0.15)
				)
				(justify left bottom)
				(hide yes)
			)
		)
		(property "Author" "Antmicro"
			(at 184.15 120.65 0)
			(effects
				(font
					(size 1.27 1.27)
					(thickness 0.15)
				)
				(justify left bottom)
				(hide yes)
			)
		)
		(property "Voltage" ""
			(at 186.69 120.65 0)
			(effects
				(font
					(size 1.27 1.27)
				)
				(justify left bottom)
				(hide yes)
			)
		)
		(property "Dielectric" ""
			(at 189.23 120.65 0)
			(effects
				(font
					(size 1.27 1.27)
				)
				(justify left bottom)
				(hide yes)
			)
		)
		(pin "1"
		)
		(pin "2"
		)
		(instances
			(project "thunderbolt-to-10gbe-adapter"
				(path ""
					(reference "C315")
					(unit 1)
				)
			)
		)
	)
	(symbol
		(lib_id "antmicroCapacitors0402:C_1u_25V_0402")
		(at 337.82 173.99 90)
		(unit 1)
		(exclude_from_sim no)
		(in_bom yes)
		(on_board yes)
		(dnp no)
		(property "Reference" "C324"
			(at 340.106 170.18 90)
			(effects
				(font
					(size 1.27 1.27)
					(thickness 0.15)
				)
				(justify right)
			)
		)
		(property "Value" "C_1u_25V_0402"
			(at 347.98 153.67 0)
			(effects
				(font
					(size 1.27 1.27)
					(thickness 0.15)
				)
				(justify left bottom)
				(hide yes)
			)
		)
		(property "Footprint" "antmicro-footprints:C_0402_1005Metric"
			(at 350.52 153.67 0)
			(effects
				(font
					(size 1.27 1.27)
					(thickness 0.15)
				)
				(justify left bottom)
				(hide yes)
			)
		)
		(property "Datasheet" "https://www.murata.com/products/productdetail?partno=GRM155R61E105KE11%23"
			(at 353.06 153.67 0)
			(effects
				(font
					(size 1.27 1.27)
					(thickness 0.15)
				)
				(justify left bottom)
				(hide yes)
			)
		)
		(property "Description" "SMD Multilayer Ceramic Capacitor, 1 µF, 25 V, 0402 [1005 Metric], ± 10%, X5R, GRM Series"
			(at 337.82 173.99 0)
			(effects
				(font
					(size 1.27 1.27)
				)
				(hide yes)
			)
		)
		(property "MPN" "GRM155R61E105KE11J"
			(at 355.6 153.67 0)
			(effects
				(font
					(size 1.27 1.27)
					(thickness 0.15)
				)
				(justify left bottom)
				(hide yes)
			)
		)
		(property "Manufacturer" "Murata"
			(at 358.14 153.67 0)
			(effects
				(font
					(size 1.27 1.27)
					(thickness 0.15)
				)
				(justify left bottom)
				(hide yes)
			)
		)
		(property "License" "Apache-2.0"
			(at 360.68 153.67 0)
			(effects
				(font
					(size 1.27 1.27)
					(thickness 0.15)
				)
				(justify left bottom)
				(hide yes)
			)
		)
		(property "Author" "Antmicro"
			(at 363.22 153.67 0)
			(effects
				(font
					(size 1.27 1.27)
					(thickness 0.15)
				)
				(justify left bottom)
				(hide yes)
			)
		)
		(property "Val" "1u"
			(at 340.106 172.72 90)
			(effects
				(font
					(size 1.27 1.27)
					(thickness 0.15)
				)
				(justify right)
			)
		)
		(property "Voltage" "25V"
			(at 365.76 153.67 0)
			(effects
				(font
					(size 1.27 1.27)
				)
				(justify left bottom)
				(hide yes)
			)
		)
		(property "Dielectric" "X5R"
			(at 368.3 153.67 0)
			(effects
				(font
					(size 1.27 1.27)
				)
				(justify left bottom)
				(hide yes)
			)
		)
		(pin "2"
		)
		(pin "1"
		)
		(instances
			(project "thunderbolt-to-10gbe-adapter"
				(path ""
					(reference "C324")
					(unit 1)
				)
			)
		)
	)
	(symbol
		(lib_id "antmicropower:PWR_FLAG")
		(at 270.51 121.92 0)
		(unit 1)
		(exclude_from_sim no)
		(in_bom yes)
		(on_board yes)
		(dnp no)
		(property "Reference" "#FLG036"
			(at 270.51 120.015 0)
			(effects
				(font
					(size 1.27 1.27)
				)
				(hide yes)
			)
		)
		(property "Value" "PWR_FLAG"
			(at 270.51 117.856 0)
			(effects
				(font
					(size 1.27 1.27)
				)
			)
		)
		(property "Footprint" ""
			(at 270.51 121.92 0)
			(effects
				(font
					(size 1.27 1.27)
				)
				(hide yes)
			)
		)
		(property "Datasheet" ""
			(at 270.51 121.92 0)
			(effects
				(font
					(size 1.27 1.27)
				)
				(hide yes)
			)
		)
		(property "Description" ""
			(at 270.51 121.92 0)
			(effects
				(font
					(size 1.27 1.27)
				)
				(hide yes)
			)
		)
		(pin "1"
		)
		(instances
			(project "thunderbolt-to-10gbe-adapter"
				(path ""
					(reference "#FLG036")
					(unit 1)
				)
			)
		)
	)
	(symbol
		(lib_id "antmicropower:GND")
		(at 270.51 137.16 0)
		(unit 1)
		(exclude_from_sim no)
		(in_bom yes)
		(on_board yes)
		(dnp no)
		(property "Reference" "#PWR0487"
			(at 270.51 143.51 0)
			(effects
				(font
					(size 1.27 1.27)
				)
				(justify left bottom)
				(hide yes)
			)
		)
		(property "Value" "GND"
			(at 270.51 140.97 0)
			(effects
				(font
					(size 1.27 1.27)
					(thickness 0.15)
				)
			)
		)
		(property "Footprint" ""
			(at 279.4 144.78 0)
			(effects
				(font
					(size 1.27 1.27)
					(thickness 0.15)
				)
				(justify left bottom)
				(hide yes)
			)
		)
		(property "Datasheet" ""
			(at 279.4 149.86 0)
			(effects
				(font
					(size 1.27 1.27)
					(thickness 0.15)
				)
				(justify left bottom)
				(hide yes)
			)
		)
		(property "Description" ""
			(at 270.51 137.16 0)
			(effects
				(font
					(size 1.27 1.27)
				)
				(hide yes)
			)
		)
		(property "Author" "Antmicro"
			(at 279.4 144.78 0)
			(effects
				(font
					(size 1.27 1.27)
					(thickness 0.15)
				)
				(justify left bottom)
				(hide yes)
			)
		)
		(property "License" "Apache-2.0"
			(at 279.4 147.32 0)
			(effects
				(font
					(size 1.27 1.27)
					(thickness 0.15)
				)
				(justify left bottom)
				(hide yes)
			)
		)
		(pin "1"
		)
		(instances
			(project "thunderbolt-to-10gbe-adapter"
				(path ""
					(reference "#PWR0487")
					(unit 1)
				)
			)
		)
	)
	(symbol
		(lib_id "antmicroTransistorsFETsMOSFETsSingle:SQS401EN-T1_BE3")
		(at 327.66 128.27 90)
		(unit 1)
		(exclude_from_sim no)
		(in_bom yes)
		(on_board yes)
		(dnp no)
		(property "Reference" "Q7"
			(at 325.12 115.57 90)
			(effects
				(font
					(size 1.27 1.27)
					(thickness 0.15)
				)
			)
		)
		(property "Value" "SQS401EN-T1_BE3"
			(at 337.82 113.03 0)
			(effects
				(font
					(size 1.27 1.27)
					(thickness 0.15)
				)
				(justify left bottom)
				(hide yes)
			)
		)
		(property "Footprint" "antmicro-footprints:Vishay_PowerPAK_1212-8_Single"
			(at 340.36 113.03 0)
			(effects
				(font
					(size 1.27 1.27)
					(thickness 0.15)
				)
				(justify left bottom)
				(hide yes)
			)
		)
		(property "Datasheet" "https://www.vishay.com/docs/65529/sqs401en.pdf"
			(at 342.9 113.03 0)
			(effects
				(font
					(size 1.27 1.27)
					(thickness 0.15)
				)
				(justify left bottom)
				(hide yes)
			)
		)
		(property "Description" "MOSFET, P Channel, 40 V, 16A, 0.047 ohm, PowerPAK 1212-8, Surface Mount"
			(at 327.66 128.27 0)
			(effects
				(font
					(size 1.27 1.27)
				)
				(hide yes)
			)
		)
		(property "MPN" "SQS401EN-T1_BE3"
			(at 325.12 118.11 90)
			(effects
				(font
					(size 1.27 1.27)
					(thickness 0.15)
				)
			)
		)
		(property "Manufacturer" "Vishay"
			(at 345.44 113.03 0)
			(effects
				(font
					(size 1.27 1.27)
					(thickness 0.15)
				)
				(justify left bottom)
				(hide yes)
			)
		)
		(property "Author" "Antmicro"
			(at 347.98 113.03 0)
			(effects
				(font
					(size 1.27 1.27)
					(thickness 0.15)
				)
				(justify left bottom)
				(hide yes)
			)
		)
		(property "License" "Apache-2.0"
			(at 350.52 113.03 0)
			(effects
				(font
					(size 1.27 1.27)
					(thickness 0.15)
				)
				(justify left bottom)
				(hide yes)
			)
		)
		(pin "4"
		)
		(pin "1"
		)
		(pin "3"
		)
		(pin "5"
		)
		(pin "2"
		)
		(instances
			(project "thunderbolt-to-10gbe-adapter"
				(path ""
					(reference "Q7")
					(unit 1)
				)
			)
		)
	)
	(symbol
		(lib_id "antmicropower:+5V")
		(at 325.12 194.31 0)
		(unit 1)
		(exclude_from_sim no)
		(in_bom yes)
		(on_board yes)
		(dnp no)
		(property "Reference" "#PWR0491"
			(at 340.36 196.85 0)
			(effects
				(font
					(size 1.27 1.27)
					(thickness 0.15)
				)
				(justify left bottom)
				(hide yes)
			)
		)
		(property "Value" "+5V_USB"
			(at 325.12 190.5 0)
			(effects
				(font
					(size 1.27 1.27)
					(thickness 0.15)
				)
			)
		)
		(property "Footprint" ""
			(at 340.36 201.93 0)
			(effects
				(font
					(size 1.27 1.27)
					(thickness 0.15)
				)
				(justify left bottom)
				(hide yes)
			)
		)
		(property "Datasheet" ""
			(at 340.36 204.47 0)
			(effects
				(font
					(size 1.27 1.27)
					(thickness 0.15)
				)
				(justify left bottom)
				(hide yes)
			)
		)
		(property "Description" ""
			(at 340.36 207.01 0)
			(effects
				(font
					(size 1.27 1.27)
				)
				(justify left bottom)
				(hide yes)
			)
		)
		(property "Author" "Antmicro"
			(at 340.36 201.93 0)
			(effects
				(font
					(size 1.27 1.27)
					(thickness 0.15)
				)
				(justify left bottom)
				(hide yes)
			)
		)
		(property "License" "Apache-2.0"
			(at 340.36 204.47 0)
			(effects
				(font
					(size 1.27 1.27)
					(thickness 0.15)
				)
				(justify left bottom)
				(hide yes)
			)
		)
		(pin "1"
		)
		(instances
			(project "thunderbolt-to-10gbe-adapter"
				(path ""
					(reference "#PWR0491")
					(unit 1)
				)
			)
		)
	)
	(symbol
		(lib_id "antmicroWire2BoardConnectors:Molex_Nano-Fit_1x2_105313-2202_Horizontal")
		(at 64.77 138.43 0)
		(mirror y)
		(unit 1)
		(exclude_from_sim no)
		(in_bom yes)
		(on_board yes)
		(dnp no)
		(fields_autoplaced yes)
		(property "Reference" "J5"
			(at 60.325 130.81 0)
			(effects
				(font
					(size 1.27 1.27)
					(thickness 0.15)
				)
			)
		)
		(property "Value" "Molex_Nano-Fit_1x2_105313-2202_Horizontal"
			(at 44.45 146.05 0)
			(effects
				(font
					(size 1.27 1.27)
					(thickness 0.15)
				)
				(justify left bottom)
				(hide yes)
			)
		)
		(property "Footprint" "antmicro-footprints:Conn_Molex_Nano-Fit_1x2_105313-2202_Horizontal"
			(at 44.45 148.59 0)
			(effects
				(font
					(size 1.27 1.27)
					(thickness 0.15)
				)
				(justify left bottom)
				(hide yes)
			)
		)
		(property "Datasheet" "https://tools.molex.com/pdm_docs/sd/1053132202_sd.pdf"
			(at 44.45 151.13 0)
			(effects
				(font
					(size 1.27 1.27)
					(thickness 0.15)
				)
				(justify left bottom)
				(hide yes)
			)
		)
		(property "Description" "Pin Header, Power, 2.5 mm, 1 Rows, 2 Contacts, Through Hole Horizontal, Nano-Fit"
			(at 44.45 161.29 0)
			(effects
				(font
					(size 1.27 1.27)
				)
				(justify left bottom)
				(hide yes)
			)
		)
		(property "MPN" "105313-2202"
			(at 60.325 133.35 0)
			(effects
				(font
					(size 1.27 1.27)
					(thickness 0.15)
				)
			)
		)
		(property "Manufacturer" "Molex"
			(at 44.45 153.67 0)
			(effects
				(font
					(size 1.27 1.27)
					(thickness 0.15)
				)
				(justify left bottom)
				(hide yes)
			)
		)
		(property "Author" "Antmicro"
			(at 44.45 156.21 0)
			(effects
				(font
					(size 1.27 1.27)
					(thickness 0.15)
				)
				(justify left bottom)
				(hide yes)
			)
		)
		(property "License" "Apache-2.0"
			(at 44.45 158.75 0)
			(effects
				(font
					(size 1.27 1.27)
					(thickness 0.15)
				)
				(justify left bottom)
				(hide yes)
			)
		)
		(pin "2"
		)
		(pin "1"
		)
		(instances
			(project "thunderbolt-to-10gbe-adapter"
				(path ""
					(reference "J5")
					(unit 1)
				)
			)
		)
	)
	(symbol
		(lib_id "antmicroTVSDiodes:PESD5Z5_0F")
		(at 346.71 168.91 270)
		(unit 1)
		(exclude_from_sim no)
		(in_bom yes)
		(on_board yes)
		(dnp no)
		(property "Reference" "D17"
			(at 348.234 170.434 90)
			(effects
				(font
					(size 1.27 1.27)
				)
				(justify left)
			)
		)
		(property "Value" "PESD5Z5.0F"
			(at 331.47 190.5 0)
			(effects
				(font
					(size 1.27 1.27)
					(thickness 0.15)
				)
				(justify left bottom)
				(hide yes)
			)
		)
		(property "Footprint" "antmicro-footprints:SOD-523"
			(at 341.63 184.15 0)
			(effects
				(font
					(size 1.27 1.27)
					(thickness 0.15)
				)
				(justify left bottom)
				(hide yes)
			)
		)
		(property "Datasheet" "https://assets.nexperia.com/documents/data-sheet/PESD5Z5_0.pdf"
			(at 339.09 184.15 0)
			(effects
				(font
					(size 1.27 1.27)
					(thickness 0.15)
				)
				(justify left bottom)
				(hide yes)
			)
		)
		(property "Description" "Unidirectional TVS, 30 kV,  SOD-523, 5 V, 89 pF"
			(at 326.39 184.15 0)
			(effects
				(font
					(size 1.27 1.27)
				)
				(justify left bottom)
				(hide yes)
			)
		)
		(property "Manufacturer" "Nexperia"
			(at 336.55 184.15 0)
			(effects
				(font
					(size 1.27 1.27)
					(thickness 0.15)
				)
				(justify left bottom)
				(hide yes)
			)
		)
		(property "MPN" "PESD5Z5.0F"
			(at 348.234 172.974 90)
			(effects
				(font
					(size 1.27 1.27)
					(thickness 0.15)
				)
				(justify left bottom)
			)
		)
		(property "Author" "Antmicro"
			(at 331.47 184.15 0)
			(effects
				(font
					(size 1.27 1.27)
					(thickness 0.15)
				)
				(justify left bottom)
				(hide yes)
			)
		)
		(property "License" "Apache-2.0"
			(at 328.93 184.15 0)
			(effects
				(font
					(size 1.27 1.27)
					(thickness 0.15)
				)
				(justify left bottom)
				(hide yes)
			)
		)
		(pin "1"
		)
		(pin "2"
		)
		(instances
			(project "thunderbolt-to-10gbe-adapter"
				(path ""
					(reference "D17")
					(unit 1)
				)
			)
		)
	)
	(symbol
		(lib_id "antmicropower:GND")
		(at 337.82 129.54 0)
		(unit 1)
		(exclude_from_sim no)
		(in_bom yes)
		(on_board yes)
		(dnp no)
		(fields_autoplaced yes)
		(property "Reference" "#PWR0493"
			(at 337.82 135.89 0)
			(effects
				(font
					(size 1.27 1.27)
				)
				(hide yes)
			)
		)
		(property "Value" "GND"
			(at 335.915 133.985 0)
			(effects
				(font
					(size 1.27 1.27)
					(thickness 0.15)
				)
				(justify left bottom)
			)
		)
		(property "Footprint" ""
			(at 346.71 137.16 0)
			(effects
				(font
					(size 1.27 1.27)
					(thickness 0.15)
				)
				(justify left bottom)
				(hide yes)
			)
		)
		(property "Datasheet" ""
			(at 346.71 142.24 0)
			(effects
				(font
					(size 1.27 1.27)
					(thickness 0.15)
				)
				(justify left bottom)
				(hide yes)
			)
		)
		(property "Description" ""
			(at 337.82 129.54 0)
			(effects
				(font
					(size 1.27 1.27)
				)
			)
		)
		(property "Author" "Antmicro"
			(at 346.71 134.62 0)
			(effects
				(font
					(size 1.27 1.27)
					(thickness 0.15)
				)
				(justify left bottom)
				(hide yes)
			)
		)
		(property "License" "Apache-2.0"
			(at 346.71 137.16 0)
			(effects
				(font
					(size 1.27 1.27)
					(thickness 0.15)
				)
				(justify left bottom)
				(hide yes)
			)
		)
		(pin "1"
		)
		(instances
			(project "thunderbolt-to-10gbe-adapter"
				(path ""
					(reference "#PWR0493")
					(unit 1)
				)
			)
		)
	)
	(symbol
		(lib_id "antmicroResistors0402:R_100k_0402")
		(at 149.86 140.97 90)
		(unit 1)
		(exclude_from_sim no)
		(in_bom yes)
		(on_board yes)
		(dnp no)
		(property "Reference" "R230"
			(at 151.13 137.16 90)
			(effects
				(font
					(size 1.27 1.27)
					(thickness 0.15)
				)
				(justify right)
			)
		)
		(property "Value" "R_100k_0402"
			(at 162.56 120.65 0)
			(effects
				(font
					(size 1.27 1.27)
					(thickness 0.15)
				)
				(justify left bottom)
				(hide yes)
			)
		)
		(property "Footprint" "antmicro-footprints:R_0402_1005Metric"
			(at 165.1 120.65 0)
			(effects
				(font
					(size 1.27 1.27)
					(thickness 0.15)
				)
				(justify left bottom)
				(hide yes)
			)
		)
		(property "Datasheet" "https://www.bourns.com/docs/product-datasheets/cr.pdf"
			(at 167.64 120.65 0)
			(effects
				(font
					(size 1.27 1.27)
					(thickness 0.15)
				)
				(justify left bottom)
				(hide yes)
			)
		)
		(property "Description" "SMD Chip Resistor, 100 kohm, ± 1%, 62.5 mW, 0402 [1005 Metric], Thick Film, General Purpose"
			(at 180.34 120.65 0)
			(effects
				(font
					(size 1.27 1.27)
				)
				(justify left bottom)
				(hide yes)
			)
		)
		(property "MPN" "CR0402-FX-1003GLF"
			(at 170.18 120.65 0)
			(effects
				(font
					(size 1.27 1.27)
					(thickness 0.15)
				)
				(justify left bottom)
				(hide yes)
			)
		)
		(property "Manufacturer" "Bourns"
			(at 172.72 120.65 0)
			(effects
				(font
					(size 1.27 1.27)
					(thickness 0.15)
				)
				(justify left bottom)
				(hide yes)
			)
		)
		(property "License" "Apache-2.0"
			(at 175.26 120.65 0)
			(effects
				(font
					(size 1.27 1.27)
					(thickness 0.15)
				)
				(justify left bottom)
				(hide yes)
			)
		)
		(property "Author" "Antmicro"
			(at 177.8 120.65 0)
			(effects
				(font
					(size 1.27 1.27)
					(thickness 0.15)
				)
				(justify left bottom)
				(hide yes)
			)
		)
		(property "Val" "100k"
			(at 151.13 139.7 90)
			(effects
				(font
					(size 1.27 1.27)
					(thickness 0.15)
				)
				(justify right)
			)
		)
		(property "Tolerance" "1%"
			(at 160.02 120.65 0)
			(effects
				(font
					(size 1.27 1.27)
				)
				(justify left bottom)
				(hide yes)
			)
		)
		(pin "2"
		)
		(pin "1"
		)
		(instances
			(project "thunderbolt-to-10gbe-adapter"
				(path ""
					(reference "R230")
					(unit 1)
				)
			)
		)
	)
	(symbol
		(lib_id "antmicroTestPoints:TP_0.75mm_SMD")
		(at 332.74 203.2 0)
		(unit 1)
		(exclude_from_sim no)
		(in_bom no)
		(on_board yes)
		(dnp no)
		(fields_autoplaced yes)
		(property "Reference" "TP2"
			(at 337.82 203.2 0)
			(effects
				(font
					(size 1.27 1.27)
					(thickness 0.15)
				)
				(justify left)
			)
		)
		(property "Value" "TP_0.75mm_SMD"
			(at 342.9 207.01 0)
			(effects
				(font
					(size 1.27 1.27)
					(thickness 0.15)
				)
				(justify left bottom)
				(hide yes)
			)
		)
		(property "Footprint" "antmicro-footprints:TP_SMD_0.75mm"
			(at 342.9 209.55 0)
			(effects
				(font
					(size 1.27 1.27)
					(thickness 0.15)
				)
				(justify left bottom)
				(hide yes)
			)
		)
		(property "Datasheet" ""
			(at 350.52 215.9 0)
			(effects
				(font
					(size 1.27 1.27)
					(thickness 0.15)
				)
				(justify left bottom)
				(hide yes)
			)
		)
		(property "Description" "SMT test point"
			(at 343.535 217.17 0)
			(effects
				(font
					(size 1.27 1.27)
				)
				(justify left bottom)
				(hide yes)
			)
		)
		(property "MPN" ""
			(at 343.535 214.63 0)
			(effects
				(font
					(size 1.27 1.27)
					(thickness 0.15)
				)
				(justify left bottom)
				(hide yes)
			)
		)
		(property "Manufacturer" ""
			(at 343.535 209.55 0)
			(effects
				(font
					(size 1.27 1.27)
					(thickness 0.15)
				)
				(justify left bottom)
				(hide yes)
			)
		)
		(property "Author" "Antmicro"
			(at 342.9 212.09 0)
			(effects
				(font
					(size 1.27 1.27)
					(thickness 0.15)
				)
				(justify left bottom)
				(hide yes)
			)
		)
		(property "License" "Apache-2.0"
			(at 342.9 214.63 0)
			(effects
				(font
					(size 1.27 1.27)
					(thickness 0.15)
				)
				(justify left bottom)
				(hide yes)
			)
		)
		(pin "1"
		)
		(instances
			(project "thunderbolt-to-10gbe-adapter"
				(path ""
					(reference "TP2")
					(unit 1)
				)
			)
		)
	)
	(symbol
		(lib_id "antmicropower:GND")
		(at 353.06 142.24 0)
		(unit 1)
		(exclude_from_sim no)
		(in_bom yes)
		(on_board yes)
		(dnp no)
		(property "Reference" "#PWR0497"
			(at 353.06 148.59 0)
			(effects
				(font
					(size 1.27 1.27)
				)
				(justify left bottom)
				(hide yes)
			)
		)
		(property "Value" "GND"
			(at 353.06 146.05 0)
			(effects
				(font
					(size 1.27 1.27)
					(thickness 0.15)
				)
			)
		)
		(property "Footprint" ""
			(at 361.95 149.86 0)
			(effects
				(font
					(size 1.27 1.27)
					(thickness 0.15)
				)
				(justify left bottom)
				(hide yes)
			)
		)
		(property "Datasheet" ""
			(at 361.95 154.94 0)
			(effects
				(font
					(size 1.27 1.27)
					(thickness 0.15)
				)
				(justify left bottom)
				(hide yes)
			)
		)
		(property "Description" ""
			(at 353.06 142.24 0)
			(effects
				(font
					(size 1.27 1.27)
				)
				(hide yes)
			)
		)
		(property "Author" "Antmicro"
			(at 361.95 149.86 0)
			(effects
				(font
					(size 1.27 1.27)
					(thickness 0.15)
				)
				(justify left bottom)
				(hide yes)
			)
		)
		(property "License" "Apache-2.0"
			(at 361.95 152.4 0)
			(effects
				(font
					(size 1.27 1.27)
					(thickness 0.15)
				)
				(justify left bottom)
				(hide yes)
			)
		)
		(pin "1"
		)
		(instances
			(project "thunderbolt-to-10gbe-adapter"
				(path ""
					(reference "#PWR0497")
					(unit 1)
				)
			)
		)
	)
	(symbol
		(lib_id "antmicropower:GND")
		(at 245.11 130.81 0)
		(unit 1)
		(exclude_from_sim no)
		(in_bom yes)
		(on_board yes)
		(dnp no)
		(property "Reference" "#PWR0484"
			(at 245.11 137.16 0)
			(effects
				(font
					(size 1.27 1.27)
				)
				(justify left bottom)
				(hide yes)
			)
		)
		(property "Value" "GND"
			(at 245.11 134.62 0)
			(effects
				(font
					(size 1.27 1.27)
					(thickness 0.15)
				)
			)
		)
		(property "Footprint" ""
			(at 254 138.43 0)
			(effects
				(font
					(size 1.27 1.27)
					(thickness 0.15)
				)
				(justify left bottom)
				(hide yes)
			)
		)
		(property "Datasheet" ""
			(at 254 143.51 0)
			(effects
				(font
					(size 1.27 1.27)
					(thickness 0.15)
				)
				(justify left bottom)
				(hide yes)
			)
		)
		(property "Description" ""
			(at 245.11 130.81 0)
			(effects
				(font
					(size 1.27 1.27)
				)
				(hide yes)
			)
		)
		(property "Author" "Antmicro"
			(at 254 138.43 0)
			(effects
				(font
					(size 1.27 1.27)
					(thickness 0.15)
				)
				(justify left bottom)
				(hide yes)
			)
		)
		(property "License" "Apache-2.0"
			(at 254 140.97 0)
			(effects
				(font
					(size 1.27 1.27)
					(thickness 0.15)
				)
				(justify left bottom)
				(hide yes)
			)
		)
		(pin "1"
		)
		(instances
			(project "thunderbolt-to-10gbe-adapter"
				(path ""
					(reference "#PWR0484")
					(unit 1)
				)
			)
		)
	)
	(symbol
		(lib_id "antmicropower:GND")
		(at 120.65 124.46 0)
		(unit 1)
		(exclude_from_sim no)
		(in_bom yes)
		(on_board yes)
		(dnp no)
		(fields_autoplaced yes)
		(property "Reference" "#PWR0475"
			(at 120.65 130.81 0)
			(effects
				(font
					(size 1.27 1.27)
				)
				(justify left bottom)
				(hide yes)
			)
		)
		(property "Value" "GND"
			(at 120.65 128.27 0)
			(effects
				(font
					(size 1.27 1.27)
					(thickness 0.15)
				)
			)
		)
		(property "Footprint" ""
			(at 129.54 132.08 0)
			(effects
				(font
					(size 1.27 1.27)
					(thickness 0.15)
				)
				(justify left bottom)
				(hide yes)
			)
		)
		(property "Datasheet" ""
			(at 129.54 137.16 0)
			(effects
				(font
					(size 1.27 1.27)
					(thickness 0.15)
				)
				(justify left bottom)
				(hide yes)
			)
		)
		(property "Description" ""
			(at 120.65 124.46 0)
			(effects
				(font
					(size 1.27 1.27)
				)
				(hide yes)
			)
		)
		(property "Author" "Antmicro"
			(at 129.54 132.08 0)
			(effects
				(font
					(size 1.27 1.27)
					(thickness 0.15)
				)
				(justify left bottom)
				(hide yes)
			)
		)
		(property "License" "Apache-2.0"
			(at 129.54 134.62 0)
			(effects
				(font
					(size 1.27 1.27)
					(thickness 0.15)
				)
				(justify left bottom)
				(hide yes)
			)
		)
		(pin "1"
		)
		(instances
			(project "thunderbolt-to-10gbe-adapter"
				(path ""
					(reference "#PWR0475")
					(unit 1)
				)
			)
		)
	)
	(symbol
		(lib_id "antmicroResistors0402:R_1k_0402")
		(at 288.29 132.08 90)
		(unit 1)
		(exclude_from_sim no)
		(in_bom yes)
		(on_board yes)
		(dnp no)
		(property "Reference" "R235"
			(at 287.02 128.27 90)
			(effects
				(font
					(size 1.27 1.27)
					(thickness 0.15)
				)
				(justify left)
			)
		)
		(property "Value" "R_1k_0402"
			(at 300.99 111.76 0)
			(effects
				(font
					(size 1.27 1.27)
					(thickness 0.15)
				)
				(justify left bottom)
				(hide yes)
			)
		)
		(property "Footprint" "antmicro-footprints:R_0402_1005Metric"
			(at 303.53 111.76 0)
			(effects
				(font
					(size 1.27 1.27)
					(thickness 0.15)
				)
				(justify left bottom)
				(hide yes)
			)
		)
		(property "Datasheet" "https://www.bourns.com/docs/product-datasheets/cr.pdf"
			(at 306.07 111.76 0)
			(effects
				(font
					(size 1.27 1.27)
					(thickness 0.15)
				)
				(justify left bottom)
				(hide yes)
			)
		)
		(property "Description" "SMD Chip Resistor, 1 kohm, ± 1%, 63 mW, 0402 [1005 Metric], Thick Film, General Purpose"
			(at 318.77 111.76 0)
			(effects
				(font
					(size 1.27 1.27)
				)
				(justify left bottom)
				(hide yes)
			)
		)
		(property "MPN" "CR0402-FX-1001GLF"
			(at 308.61 111.76 0)
			(effects
				(font
					(size 1.27 1.27)
					(thickness 0.15)
				)
				(justify left bottom)
				(hide yes)
			)
		)
		(property "Manufacturer" "Bourns"
			(at 311.15 111.76 0)
			(effects
				(font
					(size 1.27 1.27)
					(thickness 0.15)
				)
				(justify left bottom)
				(hide yes)
			)
		)
		(property "License" "Apache-2.0"
			(at 313.69 111.76 0)
			(effects
				(font
					(size 1.27 1.27)
					(thickness 0.15)
				)
				(justify left bottom)
				(hide yes)
			)
		)
		(property "Author" "Antmicro"
			(at 316.23 111.76 0)
			(effects
				(font
					(size 1.27 1.27)
					(thickness 0.15)
				)
				(justify left bottom)
				(hide yes)
			)
		)
		(property "Val" "1k"
			(at 287.02 130.81 90)
			(effects
				(font
					(size 1.27 1.27)
					(thickness 0.15)
				)
				(justify left)
			)
		)
		(property "Tolerance" "1%"
			(at 298.45 111.76 0)
			(effects
				(font
					(size 1.27 1.27)
				)
				(justify left bottom)
				(hide yes)
			)
		)
		(pin "1"
		)
		(pin "2"
		)
		(instances
			(project "thunderbolt-to-10gbe-adapter"
				(path ""
					(reference "R235")
					(unit 1)
				)
			)
		)
	)
	(symbol
		(lib_id "antmicroFixedInductors:L_3u3_6A_Bourns-SRP7028A")
		(at 218.44 121.92 0)
		(unit 1)
		(exclude_from_sim no)
		(in_bom yes)
		(on_board yes)
		(dnp no)
		(fields_autoplaced yes)
		(property "Reference" "L14"
			(at 220.98 116.84 0)
			(effects
				(font
					(size 1.27 1.27)
					(thickness 0.15)
				)
			)
		)
		(property "Value" "L_3u3_6A_Bourns-SRP7028A"
			(at 232.41 127 0)
			(effects
				(font
					(size 1.27 1.27)
					(thickness 0.15)
				)
				(justify left bottom)
				(hide yes)
			)
		)
		(property "Footprint" "antmicro-footprints:L_Bourns-SRP7028A"
			(at 232.41 129.54 0)
			(effects
				(font
					(size 1.27 1.27)
					(thickness 0.15)
				)
				(justify left bottom)
				(hide yes)
			)
		)
		(property "Datasheet" "https://www.bourns.com/docs/Product-Datasheets/SRP7028A.pdf"
			(at 232.41 132.08 0)
			(effects
				(font
					(size 1.27 1.27)
					(thickness 0.15)
				)
				(justify left bottom)
				(hide yes)
			)
		)
		(property "Description" "Power Inductor (SMD), 3.3 µH, 6 A, 28 mOhm, Shielded, 12 A, SRP7028A Series"
			(at 232.41 152.4 0)
			(effects
				(font
					(size 1.27 1.27)
				)
				(justify left bottom)
				(hide yes)
			)
		)
		(property "Val" "3u3/6A"
			(at 220.98 119.38 0)
			(effects
				(font
					(size 1.27 1.27)
					(thickness 0.15)
				)
			)
		)
		(property "Manufacturer" "Bourns"
			(at 232.41 134.62 0)
			(effects
				(font
					(size 1.27 1.27)
					(thickness 0.15)
				)
				(justify left bottom)
				(hide yes)
			)
		)
		(property "MPN" "SRP7028A-3R3M"
			(at 232.41 137.16 0)
			(effects
				(font
					(size 1.27 1.27)
					(thickness 0.15)
				)
				(justify left bottom)
				(hide yes)
			)
		)
		(property "ISat" "12 A"
			(at 232.41 138.43 0)
			(effects
				(font
					(size 1.27 1.27)
				)
				(justify left)
				(hide yes)
			)
		)
		(property "IMax" "6 A"
			(at 232.41 142.24 0)
			(effects
				(font
					(size 1.27 1.27)
					(thickness 0.15)
				)
				(justify left bottom)
				(hide yes)
			)
		)
		(property "Size" "7.3x6.6x2.8"
			(at 232.41 144.78 0)
			(effects
				(font
					(size 1.27 1.27)
					(thickness 0.15)
				)
				(justify left bottom)
				(hide yes)
			)
		)
		(property "Author" "Antmicro"
			(at 232.41 147.32 0)
			(effects
				(font
					(size 1.27 1.27)
					(thickness 0.15)
				)
				(justify left bottom)
				(hide yes)
			)
		)
		(property "License" "Apache-2.0"
			(at 232.41 149.86 0)
			(effects
				(font
					(size 1.27 1.27)
					(thickness 0.15)
				)
				(justify left bottom)
				(hide yes)
			)
		)
		(pin "1"
		)
		(pin "2"
		)
		(instances
			(project "thunderbolt-to-10gbe-adapter"
				(path ""
					(reference "L14")
					(unit 1)
				)
			)
		)
	)
	(symbol
		(lib_id "antmicroResistors0402:R_3k24_0402")
		(at 101.6 142.24 90)
		(unit 1)
		(exclude_from_sim no)
		(in_bom yes)
		(on_board yes)
		(dnp no)
		(property "Reference" "R227"
			(at 102.87 138.43 90)
			(effects
				(font
					(size 1.27 1.27)
					(thickness 0.15)
				)
				(justify right)
			)
		)
		(property "Value" "R_3k24_0402"
			(at 114.3 121.92 0)
			(effects
				(font
					(size 1.27 1.27)
					(thickness 0.15)
				)
				(justify left bottom)
				(hide yes)
			)
		)
		(property "Footprint" "antmicro-footprints:R_0402_1005Metric"
			(at 116.84 121.92 0)
			(effects
				(font
					(size 1.27 1.27)
					(thickness 0.15)
				)
				(justify left bottom)
				(hide yes)
			)
		)
		(property "Datasheet" "https://www.farnell.com/datasheets/3795017.pdf"
			(at 119.38 121.92 0)
			(effects
				(font
					(size 1.27 1.27)
					(thickness 0.15)
				)
				(justify left bottom)
				(hide yes)
			)
		)
		(property "Description" "SMD Chip Resistor, 3.24 kohm, ± 1%, 62.5 mW, 0402 [1005 Metric], Thick Film, General Purpose"
			(at 132.08 121.92 0)
			(effects
				(font
					(size 1.27 1.27)
				)
				(justify left bottom)
				(hide yes)
			)
		)
		(property "MPN" "RMCF0402FT3K24"
			(at 121.92 121.92 0)
			(effects
				(font
					(size 1.27 1.27)
					(thickness 0.15)
				)
				(justify left bottom)
				(hide yes)
			)
		)
		(property "Manufacturer" "Stackpole Electronics"
			(at 124.46 121.92 0)
			(effects
				(font
					(size 1.27 1.27)
					(thickness 0.15)
				)
				(justify left bottom)
				(hide yes)
			)
		)
		(property "License" "Apache-2.0"
			(at 127 121.92 0)
			(effects
				(font
					(size 1.27 1.27)
					(thickness 0.15)
				)
				(justify left bottom)
				(hide yes)
			)
		)
		(property "Author" "Antmicro"
			(at 129.54 121.92 0)
			(effects
				(font
					(size 1.27 1.27)
					(thickness 0.15)
				)
				(justify left bottom)
				(hide yes)
			)
		)
		(property "Val" "3k24"
			(at 102.87 140.97 90)
			(effects
				(font
					(size 1.27 1.27)
					(thickness 0.15)
				)
				(justify right)
			)
		)
		(property "Tolerance" "1%"
			(at 111.76 121.92 0)
			(effects
				(font
					(size 1.27 1.27)
				)
				(justify left bottom)
				(hide yes)
			)
		)
		(pin "2"
		)
		(pin "1"
		)
		(instances
			(project "thunderbolt-to-10gbe-adapter"
				(path ""
					(reference "R227")
					(unit 1)
				)
			)
		)
	)
	(symbol
		(lib_id "antmicroPMICORControllersIdealDiodes:LTC4412IS6")
		(at 307.34 134.62 0)
		(unit 1)
		(exclude_from_sim no)
		(in_bom yes)
		(on_board yes)
		(dnp no)
		(property "Reference" "U21"
			(at 316.23 128.016 0)
			(effects
				(font
					(size 1.27 1.27)
					(thickness 0.15)
				)
			)
		)
		(property "Value" "LTC4412IS6"
			(at 339.09 139.7 0)
			(effects
				(font
					(size 1.27 1.27)
					(thickness 0.15)
				)
				(justify left bottom)
				(hide yes)
			)
		)
		(property "Footprint" "antmicro-footprints:SOT-23-6"
			(at 339.09 142.24 0)
			(effects
				(font
					(size 1.27 1.27)
					(thickness 0.15)
				)
				(justify left bottom)
				(hide yes)
			)
		)
		(property "Datasheet" "https://www.analog.com/media/en/technical-documentation/data-sheets/4412fb.pdf"
			(at 339.09 144.78 0)
			(effects
				(font
					(size 1.27 1.27)
					(thickness 0.15)
				)
				(justify left bottom)
				(hide yes)
			)
		)
		(property "Description" "Ideal diode controller"
			(at 307.34 134.62 0)
			(effects
				(font
					(size 1.27 1.27)
				)
				(hide yes)
			)
		)
		(property "MPN" "LTC4412IS6#TRMPBF"
			(at 316.23 130.556 0)
			(effects
				(font
					(size 1.27 1.27)
					(thickness 0.15)
				)
			)
		)
		(property "Manufacturer" "Analog Devices"
			(at 339.09 149.86 0)
			(effects
				(font
					(size 1.27 1.27)
					(thickness 0.15)
				)
				(justify left bottom)
				(hide yes)
			)
		)
		(property "Author" "Antmicro"
			(at 339.09 152.4 0)
			(effects
				(font
					(size 1.27 1.27)
					(thickness 0.15)
				)
				(justify left bottom)
				(hide yes)
			)
		)
		(property "License" "Apache-2.0"
			(at 339.09 154.94 0)
			(effects
				(font
					(size 1.27 1.27)
					(thickness 0.15)
				)
				(justify left bottom)
				(hide yes)
			)
		)
		(pin "6"
		)
		(pin "5"
		)
		(pin "4"
		)
		(pin "1"
		)
		(pin "3"
		)
		(pin "2"
		)
		(instances
			(project "thunderbolt-to-10gbe-adapter"
				(path ""
					(reference "U21")
					(unit 1)
				)
			)
		)
	)
	(symbol
		(lib_id "antmicroResistors0603:R_0R_22.4A_0603")
		(at 279.4 121.92 0)
		(unit 1)
		(exclude_from_sim no)
		(in_bom yes)
		(on_board yes)
		(dnp no)
		(property "Reference" "R234"
			(at 281.94 116.84 0)
			(effects
				(font
					(size 1.27 1.27)
					(thickness 0.15)
				)
			)
		)
		(property "Value" "R_0R_22.4A_0603"
			(at 294.64 127 0)
			(effects
				(font
					(size 1.27 1.27)
					(thickness 0.15)
				)
				(justify left bottom)
				(hide yes)
			)
		)
		(property "Footprint" "antmicro-footprints:R_0603_1608Metric"
			(at 294.64 132.08 0)
			(effects
				(font
					(size 1.27 1.27)
					(thickness 0.15)
				)
				(justify left bottom)
				(hide yes)
			)
		)
		(property "Datasheet" "https://fscdn.rohm.com/en/products/databook/datasheet/passive/resistor/chip_resistor/pmr-jpw-e.pdf"
			(at 294.64 134.62 0)
			(effects
				(font
					(size 1.27 1.27)
					(thickness 0.15)
				)
				(justify left bottom)
				(hide yes)
			)
		)
		(property "Description" "SMD Chip Resistor"
			(at 294.64 149.86 0)
			(effects
				(font
					(size 1.27 1.27)
				)
				(justify left bottom)
				(hide yes)
			)
		)
		(property "MPN" "PMR03EZPJ000"
			(at 294.64 137.16 0)
			(effects
				(font
					(size 1.27 1.27)
					(thickness 0.15)
				)
				(justify left bottom)
				(hide yes)
			)
		)
		(property "Manufacturer" "ROHM Semiconductor"
			(at 294.64 139.7 0)
			(effects
				(font
					(size 1.27 1.27)
					(thickness 0.15)
				)
				(justify left bottom)
				(hide yes)
			)
		)
		(property "Val" "0R"
			(at 281.94 119.38 0)
			(effects
				(font
					(size 1.27 1.27)
					(thickness 0.15)
				)
			)
		)
		(property "Max. Curr." "22.4A"
			(at 281.94 124.46 0)
			(effects
				(font
					(size 1.27 1.27)
					(thickness 0.15)
				)
			)
		)
		(property "Author" "Antmicro"
			(at 294.64 144.78 0)
			(effects
				(font
					(size 1.27 1.27)
					(thickness 0.15)
				)
				(justify left bottom)
				(hide yes)
			)
		)
		(property "License" "Apache-2.0"
			(at 294.64 147.32 0)
			(effects
				(font
					(size 1.27 1.27)
					(thickness 0.15)
				)
				(justify left bottom)
				(hide yes)
			)
		)
		(property "Tolerance" "template_tolerance"
			(at 299.72 132.08 0)
			(effects
				(font
					(size 1.27 1.27)
				)
				(justify left bottom)
				(hide yes)
			)
		)
		(pin "2"
		)
		(pin "1"
		)
		(instances
			(project "thunderbolt-to-10gbe-adapter"
				(path ""
					(reference "R234")
					(unit 1)
				)
			)
		)
	)
	(symbol
		(lib_id "antmicroTestPoints:TP_0.75mm_SMD")
		(at 332.74 200.66 0)
		(unit 1)
		(exclude_from_sim no)
		(in_bom no)
		(on_board yes)
		(dnp no)
		(fields_autoplaced yes)
		(property "Reference" "TP39"
			(at 337.82 200.66 0)
			(effects
				(font
					(size 1.27 1.27)
					(thickness 0.15)
				)
				(justify left)
			)
		)
		(property "Value" "TP_0.75mm_SMD"
			(at 342.9 204.47 0)
			(effects
				(font
					(size 1.27 1.27)
					(thickness 0.15)
				)
				(justify left bottom)
				(hide yes)
			)
		)
		(property "Footprint" "antmicro-footprints:TP_SMD_0.75mm"
			(at 342.9 207.01 0)
			(effects
				(font
					(size 1.27 1.27)
					(thickness 0.15)
				)
				(justify left bottom)
				(hide yes)
			)
		)
		(property "Datasheet" ""
			(at 350.52 213.36 0)
			(effects
				(font
					(size 1.27 1.27)
					(thickness 0.15)
				)
				(justify left bottom)
				(hide yes)
			)
		)
		(property "Description" "SMT test point"
			(at 343.535 214.63 0)
			(effects
				(font
					(size 1.27 1.27)
				)
				(justify left bottom)
				(hide yes)
			)
		)
		(property "MPN" ""
			(at 343.535 212.09 0)
			(effects
				(font
					(size 1.27 1.27)
					(thickness 0.15)
				)
				(justify left bottom)
				(hide yes)
			)
		)
		(property "Manufacturer" ""
			(at 343.535 207.01 0)
			(effects
				(font
					(size 1.27 1.27)
					(thickness 0.15)
				)
				(justify left bottom)
				(hide yes)
			)
		)
		(property "Author" "Antmicro"
			(at 342.9 209.55 0)
			(effects
				(font
					(size 1.27 1.27)
					(thickness 0.15)
				)
				(justify left bottom)
				(hide yes)
			)
		)
		(property "License" "Apache-2.0"
			(at 342.9 212.09 0)
			(effects
				(font
					(size 1.27 1.27)
					(thickness 0.15)
				)
				(justify left bottom)
				(hide yes)
			)
		)
		(pin "1"
		)
		(instances
			(project "thunderbolt-to-10gbe-adapter"
				(path ""
					(reference "TP39")
					(unit 1)
				)
			)
		)
	)
	(symbol
		(lib_id "antmicropower:PWR_FLAG")
		(at 340.36 120.65 0)
		(unit 1)
		(exclude_from_sim no)
		(in_bom yes)
		(on_board yes)
		(dnp no)
		(property "Reference" "#FLG038"
			(at 340.36 118.745 0)
			(effects
				(font
					(size 1.27 1.27)
				)
				(hide yes)
			)
		)
		(property "Value" "PWR_FLAG"
			(at 340.36 116.84 0)
			(effects
				(font
					(size 1.27 1.27)
				)
			)
		)
		(property "Footprint" ""
			(at 340.36 120.65 0)
			(effects
				(font
					(size 1.27 1.27)
				)
				(hide yes)
			)
		)
		(property "Datasheet" ""
			(at 340.36 120.65 0)
			(effects
				(font
					(size 1.27 1.27)
				)
				(hide yes)
			)
		)
		(property "Description" ""
			(at 340.36 123.19 0)
			(effects
				(font
					(size 1.27 1.27)
				)
				(justify left bottom)
				(hide yes)
			)
		)
		(pin "1"
		)
		(instances
			(project "thunderbolt-to-10gbe-adapter"
				(path ""
					(reference "#FLG038")
					(unit 1)
				)
			)
		)
	)
	(symbol
		(lib_id "antmicroResistors0402:R_10k_0402")
		(at 227.33 135.89 90)
		(unit 1)
		(exclude_from_sim no)
		(in_bom yes)
		(on_board yes)
		(dnp no)
		(property "Reference" "R232"
			(at 228.6 132.08 90)
			(effects
				(font
					(size 1.27 1.27)
					(thickness 0.15)
				)
				(justify right)
			)
		)
		(property "Value" "R_10k_0402"
			(at 240.03 115.57 0)
			(effects
				(font
					(size 1.27 1.27)
					(thickness 0.15)
				)
				(justify left bottom)
				(hide yes)
			)
		)
		(property "Footprint" "antmicro-footprints:R_0402_1005Metric"
			(at 242.57 115.57 0)
			(effects
				(font
					(size 1.27 1.27)
					(thickness 0.15)
				)
				(justify left bottom)
				(hide yes)
			)
		)
		(property "Datasheet" "https://www.bourns.com/docs/product-datasheets/cr.pdf"
			(at 245.11 115.57 0)
			(effects
				(font
					(size 1.27 1.27)
					(thickness 0.15)
				)
				(justify left bottom)
				(hide yes)
			)
		)
		(property "Description" "SMD Chip Resistor, 10 kohm, ± 1%, 62.5 mW, 0402 [1005 Metric], Thick Film, General Purpose"
			(at 227.33 135.89 0)
			(effects
				(font
					(size 1.27 1.27)
				)
				(hide yes)
			)
		)
		(property "MPN" "CR0402-FX-1002GLF"
			(at 247.65 115.57 0)
			(effects
				(font
					(size 1.27 1.27)
					(thickness 0.15)
				)
				(justify left bottom)
				(hide yes)
			)
		)
		(property "Manufacturer" "Bourns"
			(at 250.19 115.57 0)
			(effects
				(font
					(size 1.27 1.27)
					(thickness 0.15)
				)
				(justify left bottom)
				(hide yes)
			)
		)
		(property "License" "Apache-2.0"
			(at 252.73 115.57 0)
			(effects
				(font
					(size 1.27 1.27)
					(thickness 0.15)
				)
				(justify left bottom)
				(hide yes)
			)
		)
		(property "Author" "Antmicro"
			(at 255.27 115.57 0)
			(effects
				(font
					(size 1.27 1.27)
					(thickness 0.15)
				)
				(justify left bottom)
				(hide yes)
			)
		)
		(property "Val" "10k"
			(at 228.6 134.62 90)
			(effects
				(font
					(size 1.27 1.27)
					(thickness 0.15)
				)
				(justify right)
			)
		)
		(property "Tolerance" "1%"
			(at 237.49 115.57 0)
			(effects
				(font
					(size 1.27 1.27)
				)
				(justify left bottom)
				(hide yes)
			)
		)
		(pin "2"
		)
		(pin "1"
		)
		(instances
			(project "thunderbolt-to-10gbe-adapter"
				(path ""
					(reference "R232")
					(unit 1)
				)
			)
		)
	)
	(symbol
		(lib_id "antmicropower:GND")
		(at 167.64 142.24 0)
		(unit 1)
		(exclude_from_sim no)
		(in_bom yes)
		(on_board yes)
		(dnp no)
		(property "Reference" "#PWR0480"
			(at 167.64 148.59 0)
			(effects
				(font
					(size 1.27 1.27)
				)
				(justify left bottom)
				(hide yes)
			)
		)
		(property "Value" "GND"
			(at 167.64 146.05 0)
			(effects
				(font
					(size 1.27 1.27)
					(thickness 0.15)
				)
			)
		)
		(property "Footprint" ""
			(at 176.53 149.86 0)
			(effects
				(font
					(size 1.27 1.27)
					(thickness 0.15)
				)
				(justify left bottom)
				(hide yes)
			)
		)
		(property "Datasheet" ""
			(at 176.53 154.94 0)
			(effects
				(font
					(size 1.27 1.27)
					(thickness 0.15)
				)
				(justify left bottom)
				(hide yes)
			)
		)
		(property "Description" ""
			(at 167.64 142.24 0)
			(effects
				(font
					(size 1.27 1.27)
				)
				(hide yes)
			)
		)
		(property "Author" "Antmicro"
			(at 176.53 149.86 0)
			(effects
				(font
					(size 1.27 1.27)
					(thickness 0.15)
				)
				(justify left bottom)
				(hide yes)
			)
		)
		(property "License" "Apache-2.0"
			(at 176.53 152.4 0)
			(effects
				(font
					(size 1.27 1.27)
					(thickness 0.15)
				)
				(justify left bottom)
				(hide yes)
			)
		)
		(pin "1"
		)
		(instances
			(project "thunderbolt-to-10gbe-adapter"
				(path ""
					(reference "#PWR0480")
					(unit 1)
				)
			)
		)
	)
	(symbol
		(lib_id "antmicropower:GND")
		(at 111.76 143.51 0)
		(unit 1)
		(exclude_from_sim no)
		(in_bom yes)
		(on_board yes)
		(dnp no)
		(fields_autoplaced yes)
		(property "Reference" "#PWR0474"
			(at 111.76 149.86 0)
			(effects
				(font
					(size 1.27 1.27)
				)
				(justify left bottom)
				(hide yes)
			)
		)
		(property "Value" "GND"
			(at 111.76 147.32 0)
			(effects
				(font
					(size 1.27 1.27)
					(thickness 0.15)
				)
			)
		)
		(property "Footprint" ""
			(at 120.65 151.13 0)
			(effects
				(font
					(size 1.27 1.27)
					(thickness 0.15)
				)
				(justify left bottom)
				(hide yes)
			)
		)
		(property "Datasheet" ""
			(at 120.65 156.21 0)
			(effects
				(font
					(size 1.27 1.27)
					(thickness 0.15)
				)
				(justify left bottom)
				(hide yes)
			)
		)
		(property "Description" ""
			(at 111.76 143.51 0)
			(effects
				(font
					(size 1.27 1.27)
				)
				(hide yes)
			)
		)
		(property "Author" "Antmicro"
			(at 120.65 151.13 0)
			(effects
				(font
					(size 1.27 1.27)
					(thickness 0.15)
				)
				(justify left bottom)
				(hide yes)
			)
		)
		(property "License" "Apache-2.0"
			(at 120.65 153.67 0)
			(effects
				(font
					(size 1.27 1.27)
					(thickness 0.15)
				)
				(justify left bottom)
				(hide yes)
			)
		)
		(pin "1"
		)
		(instances
			(project "thunderbolt-to-10gbe-adapter"
				(path ""
					(reference "#PWR0474")
					(unit 1)
				)
			)
		)
	)
	(symbol
		(lib_id "antmicroCapacitors0402:C_100n_0402")
		(at 214.63 116.84 180)
		(unit 1)
		(exclude_from_sim no)
		(in_bom yes)
		(on_board yes)
		(dnp no)
		(fields_autoplaced yes)
		(property "Reference" "C317"
			(at 212.0836 110.49 0)
			(effects
				(font
					(size 1.27 1.27)
				)
			)
		)
		(property "Value" "C_100n_0402"
			(at 194.31 106.68 0)
			(effects
				(font
					(size 1.27 1.27)
					(thickness 0.15)
				)
				(justify left bottom)
				(hide yes)
			)
		)
		(property "Footprint" "antmicro-footprints:C_0402_1005Metric"
			(at 194.31 104.14 0)
			(effects
				(font
					(size 1.27 1.27)
					(thickness 0.15)
				)
				(justify left bottom)
				(hide yes)
			)
		)
		(property "Datasheet" "https://www.murata.com/products/productdetail?partno=GRM155R61H104KE14%23"
			(at 194.31 101.6 0)
			(effects
				(font
					(size 1.27 1.27)
					(thickness 0.15)
				)
				(justify left bottom)
				(hide yes)
			)
		)
		(property "Description" "SMD Multilayer Ceramic Capacitor, 0.1 µF, 50 V, 0402 [1005 Metric], ± 10%, X5R, GRM Series"
			(at 214.63 116.84 0)
			(effects
				(font
					(size 1.27 1.27)
				)
				(hide yes)
			)
		)
		(property "Manufacturer" "Murata"
			(at 194.31 96.52 0)
			(effects
				(font
					(size 1.27 1.27)
					(thickness 0.15)
				)
				(justify left bottom)
				(hide yes)
			)
		)
		(property "MPN" "GRM155R61H104KE14D"
			(at 194.31 99.06 0)
			(effects
				(font
					(size 1.27 1.27)
					(thickness 0.15)
				)
				(justify left bottom)
				(hide yes)
			)
		)
		(property "Val" "100n"
			(at 212.0836 113.03 0)
			(effects
				(font
					(size 1.27 1.27)
					(thickness 0.15)
				)
			)
		)
		(property "License" "Apache-2.0"
			(at 194.31 93.98 0)
			(effects
				(font
					(size 1.27 1.27)
					(thickness 0.15)
				)
				(justify left bottom)
				(hide yes)
			)
		)
		(property "Author" "Antmicro"
			(at 194.31 91.44 0)
			(effects
				(font
					(size 1.27 1.27)
					(thickness 0.15)
				)
				(justify left bottom)
				(hide yes)
			)
		)
		(property "Voltage" "50V"
			(at 194.31 88.9 0)
			(effects
				(font
					(size 1.27 1.27)
				)
				(justify left bottom)
				(hide yes)
			)
		)
		(property "Dielectric" "X5R"
			(at 194.31 86.36 0)
			(effects
				(font
					(size 1.27 1.27)
				)
				(justify left bottom)
				(hide yes)
			)
		)
		(pin "1"
		)
		(pin "2"
		)
		(instances
			(project "thunderbolt-to-10gbe-adapter"
				(path ""
					(reference "C317")
					(unit 1)
				)
			)
		)
	)
	(symbol
		(lib_id "antmicroCapacitors0402:C_4u7_25V_0402")
		(at 167.64 140.97 90)
		(unit 1)
		(exclude_from_sim no)
		(in_bom yes)
		(on_board yes)
		(dnp no)
		(property "Reference" "C316"
			(at 168.275 136.525 90)
			(effects
				(font
					(size 1.27 1.27)
					(thickness 0.15)
				)
				(justify right)
			)
		)
		(property "Value" "C_4u7_25V_0402"
			(at 177.8 120.65 0)
			(effects
				(font
					(size 1.27 1.27)
					(thickness 0.15)
				)
				(justify left bottom)
				(hide yes)
			)
		)
		(property "Footprint" "antmicro-footprints:C_0402_1005Metric"
			(at 180.34 120.65 0)
			(effects
				(font
					(size 1.27 1.27)
					(thickness 0.15)
				)
				(justify left bottom)
				(hide yes)
			)
		)
		(property "Datasheet" "https://www.murata.com/products/productdetail?partno=GRM155C61E475ME15%23"
			(at 182.88 120.65 0)
			(effects
				(font
					(size 1.27 1.27)
					(thickness 0.15)
				)
				(justify left bottom)
				(hide yes)
			)
		)
		(property "Description" "SMD Multilayer Ceramic Capacitor"
			(at 167.64 140.97 0)
			(effects
				(font
					(size 1.27 1.27)
				)
				(hide yes)
			)
		)
		(property "MPN" "GRM155C61E475ME15J"
			(at 185.42 120.65 0)
			(effects
				(font
					(size 1.27 1.27)
					(thickness 0.15)
				)
				(justify left bottom)
				(hide yes)
			)
		)
		(property "Manufacturer" "Murata"
			(at 187.96 120.65 0)
			(effects
				(font
					(size 1.27 1.27)
					(thickness 0.15)
				)
				(justify left bottom)
				(hide yes)
			)
		)
		(property "License" "Apache-2.0"
			(at 190.5 120.65 0)
			(effects
				(font
					(size 1.27 1.27)
					(thickness 0.15)
				)
				(justify left bottom)
				(hide yes)
			)
		)
		(property "Author" "Antmicro"
			(at 193.04 120.65 0)
			(effects
				(font
					(size 1.27 1.27)
					(thickness 0.15)
				)
				(justify left bottom)
				(hide yes)
			)
		)
		(property "Val" "4u7"
			(at 168.275 140.335 90)
			(effects
				(font
					(size 1.27 1.27)
					(thickness 0.15)
				)
				(justify right)
			)
		)
		(property "Voltage" "25V"
			(at 195.58 120.65 0)
			(effects
				(font
					(size 1.27 1.27)
				)
				(justify left bottom)
				(hide yes)
			)
		)
		(property "Dielectric" "X5S"
			(at 198.12 120.65 0)
			(effects
				(font
					(size 1.27 1.27)
				)
				(justify left bottom)
				(hide yes)
			)
		)
		(pin "2"
		)
		(pin "1"
		)
		(instances
			(project "thunderbolt-to-10gbe-adapter"
				(path ""
					(reference "C316")
					(unit 1)
				)
			)
		)
	)
	(symbol
		(lib_id "antmicropower:GND")
		(at 101.6 143.51 0)
		(unit 1)
		(exclude_from_sim no)
		(in_bom yes)
		(on_board yes)
		(dnp no)
		(property "Reference" "#PWR0472"
			(at 101.6 149.86 0)
			(effects
				(font
					(size 1.27 1.27)
				)
				(justify left bottom)
				(hide yes)
			)
		)
		(property "Value" "GND"
			(at 101.6 147.32 0)
			(effects
				(font
					(size 1.27 1.27)
					(thickness 0.15)
				)
			)
		)
		(property "Footprint" ""
			(at 110.49 151.13 0)
			(effects
				(font
					(size 1.27 1.27)
					(thickness 0.15)
				)
				(justify left bottom)
				(hide yes)
			)
		)
		(property "Datasheet" ""
			(at 110.49 156.21 0)
			(effects
				(font
					(size 1.27 1.27)
					(thickness 0.15)
				)
				(justify left bottom)
				(hide yes)
			)
		)
		(property "Description" ""
			(at 101.6 143.51 0)
			(effects
				(font
					(size 1.27 1.27)
				)
				(hide yes)
			)
		)
		(property "Author" "Antmicro"
			(at 110.49 151.13 0)
			(effects
				(font
					(size 1.27 1.27)
					(thickness 0.15)
				)
				(justify left bottom)
				(hide yes)
			)
		)
		(property "License" "Apache-2.0"
			(at 110.49 153.67 0)
			(effects
				(font
					(size 1.27 1.27)
					(thickness 0.15)
				)
				(justify left bottom)
				(hide yes)
			)
		)
		(pin "1"
		)
		(instances
			(project "thunderbolt-to-10gbe-adapter"
				(path ""
					(reference "#PWR0472")
					(unit 1)
				)
			)
		)
	)
	(symbol
		(lib_id "antmicropower:GND")
		(at 237.49 130.81 0)
		(unit 1)
		(exclude_from_sim no)
		(in_bom yes)
		(on_board yes)
		(dnp no)
		(property "Reference" "#PWR0483"
			(at 237.49 137.16 0)
			(effects
				(font
					(size 1.27 1.27)
				)
				(justify left bottom)
				(hide yes)
			)
		)
		(property "Value" "GND"
			(at 237.49 134.62 0)
			(effects
				(font
					(size 1.27 1.27)
					(thickness 0.15)
				)
			)
		)
		(property "Footprint" ""
			(at 246.38 138.43 0)
			(effects
				(font
					(size 1.27 1.27)
					(thickness 0.15)
				)
				(justify left bottom)
				(hide yes)
			)
		)
		(property "Datasheet" ""
			(at 246.38 143.51 0)
			(effects
				(font
					(size 1.27 1.27)
					(thickness 0.15)
				)
				(justify left bottom)
				(hide yes)
			)
		)
		(property "Description" ""
			(at 237.49 130.81 0)
			(effects
				(font
					(size 1.27 1.27)
				)
				(hide yes)
			)
		)
		(property "Author" "Antmicro"
			(at 246.38 138.43 0)
			(effects
				(font
					(size 1.27 1.27)
					(thickness 0.15)
				)
				(justify left bottom)
				(hide yes)
			)
		)
		(property "License" "Apache-2.0"
			(at 246.38 140.97 0)
			(effects
				(font
					(size 1.27 1.27)
					(thickness 0.15)
				)
				(justify left bottom)
				(hide yes)
			)
		)
		(pin "1"
		)
		(instances
			(project "thunderbolt-to-10gbe-adapter"
				(path ""
					(reference "#PWR0483")
					(unit 1)
				)
			)
		)
	)
	(symbol
		(lib_id "antmicroDCDCConverters:SIC437AED-T1-GE3")
		(at 176.53 116.84 0)
		(unit 1)
		(exclude_from_sim no)
		(in_bom yes)
		(on_board yes)
		(dnp no)
		(property "Reference" "U20"
			(at 187.325 110.49 0)
			(effects
				(font
					(size 1.27 1.27)
					(thickness 0.15)
				)
			)
		)
		(property "Value" "SIC437AED-T1-GE3"
			(at 209.55 124.46 0)
			(effects
				(font
					(size 1.27 1.27)
					(thickness 0.15)
				)
				(justify left bottom)
				(hide yes)
			)
		)
		(property "Footprint" "antmicro-footprints:MLP44-24L_4x4x0.75mm"
			(at 209.55 127 0)
			(effects
				(font
					(size 1.27 1.27)
					(thickness 0.15)
				)
				(justify left bottom)
				(hide yes)
			)
		)
		(property "Datasheet" "https://www.vishay.com/docs/75921/sic437.pdf"
			(at 209.55 129.54 0)
			(effects
				(font
					(size 1.27 1.27)
					(thickness 0.15)
				)
				(justify left bottom)
				(hide yes)
			)
		)
		(property "Description" "DC/DC Buck Step Down Regulator Adjustable, 4.5-28V In, 0.6V to 20V/12A Out, 1MHz, PowerPAK MLP44-24"
			(at 209.55 139.7 0)
			(effects
				(font
					(size 1.27 1.27)
				)
				(justify left bottom)
				(hide yes)
			)
		)
		(property "Manufacturer" "Vishay"
			(at 209.55 132.08 0)
			(effects
				(font
					(size 1.27 1.27)
					(thickness 0.15)
				)
				(justify left bottom)
				(hide yes)
			)
		)
		(property "MPN" "SIC437AED-T1-GE3"
			(at 187.325 113.03 0)
			(effects
				(font
					(size 1.27 1.27)
					(thickness 0.15)
				)
			)
		)
		(property "Author" "Antmicro"
			(at 209.55 134.62 0)
			(effects
				(font
					(size 1.27 1.27)
					(thickness 0.15)
				)
				(justify left bottom)
				(hide yes)
			)
		)
		(property "License" "Apache-2.0"
			(at 209.55 137.16 0)
			(effects
				(font
					(size 1.27 1.27)
					(thickness 0.15)
				)
				(justify left bottom)
				(hide yes)
			)
		)
		(pin "7"
		)
		(pin "16"
		)
		(pin "18"
		)
		(pin "8"
		)
		(pin "15"
		)
		(pin "14"
		)
		(pin "20"
		)
		(pin "2"
		)
		(pin "12"
		)
		(pin "22"
		)
		(pin "11"
		)
		(pin "26"
		)
		(pin "10"
		)
		(pin "19"
		)
		(pin "5"
		)
		(pin "4"
		)
		(pin "17"
		)
		(pin "6"
		)
		(pin "3"
		)
		(pin "1"
		)
		(pin "13"
		)
		(pin "23"
		)
		(pin "25"
		)
		(pin "21"
		)
		(pin "24"
		)
		(pin "9"
		)
		(pin "27"
		)
		(pin "28"
		)
		(instances
			(project "thunderbolt-to-10gbe-adapter"
				(path ""
					(reference "U20")
					(unit 1)
				)
			)
		)
	)
	(symbol
		(lib_id "antmicroResistors0402:R_499k_0402")
		(at 142.24 125.73 90)
		(unit 1)
		(exclude_from_sim no)
		(in_bom yes)
		(on_board yes)
		(dnp yes)
		(property "Reference" "R228"
			(at 143.51 121.92 90)
			(effects
				(font
					(size 1.27 1.27)
					(thickness 0.15)
				)
				(justify right)
			)
		)
		(property "Value" "R_499k_0402"
			(at 154.94 105.41 0)
			(effects
				(font
					(size 1.27 1.27)
					(thickness 0.15)
				)
				(justify left bottom)
				(hide yes)
			)
		)
		(property "Footprint" "antmicro-footprints:R_0402_1005Metric"
			(at 157.48 105.41 0)
			(effects
				(font
					(size 1.27 1.27)
					(thickness 0.15)
				)
				(justify left bottom)
				(hide yes)
			)
		)
		(property "Datasheet" "https://www.mouser.com/datasheet/2/54/cr-1858361.pdf"
			(at 160.02 105.41 0)
			(effects
				(font
					(size 1.27 1.27)
					(thickness 0.15)
				)
				(justify left bottom)
				(hide yes)
			)
		)
		(property "Description" "SMD Chip Resistor, 499 kohm, ± 1%, 63 mW, 0402 [1005 Metric], Thick Film, General Purpose"
			(at 142.24 125.73 0)
			(effects
				(font
					(size 1.27 1.27)
				)
				(hide yes)
			)
		)
		(property "MPN" "CR0402-FX-4993GLF"
			(at 162.56 105.41 0)
			(effects
				(font
					(size 1.27 1.27)
					(thickness 0.15)
				)
				(justify left bottom)
				(hide yes)
			)
		)
		(property "Manufacturer" "Bourns"
			(at 165.1 105.41 0)
			(effects
				(font
					(size 1.27 1.27)
					(thickness 0.15)
				)
				(justify left bottom)
				(hide yes)
			)
		)
		(property "License" "Apache-2.0"
			(at 167.64 105.41 0)
			(effects
				(font
					(size 1.27 1.27)
					(thickness 0.15)
				)
				(justify left bottom)
				(hide yes)
			)
		)
		(property "Author" "Antmicro"
			(at 170.18 105.41 0)
			(effects
				(font
					(size 1.27 1.27)
					(thickness 0.15)
				)
				(justify left bottom)
				(hide yes)
			)
		)
		(property "Val" "499k"
			(at 143.51 124.46 90)
			(effects
				(font
					(size 1.27 1.27)
					(thickness 0.15)
				)
				(justify right)
			)
		)
		(property "Tolerance" "1%"
			(at 152.4 105.41 0)
			(effects
				(font
					(size 1.27 1.27)
				)
				(justify left bottom)
				(hide yes)
			)
		)
		(pin "2"
		)
		(pin "1"
		)
		(instances
			(project "thunderbolt-to-10gbe-adapter"
				(path ""
					(reference "R228")
					(unit 1)
				)
			)
		)
	)
	(symbol
		(lib_id "antmicroLEDIndicationDiscrete:LED_G_0603_LTST-C190GKT")
		(at 353.06 140.97 90)
		(unit 1)
		(exclude_from_sim no)
		(in_bom yes)
		(on_board yes)
		(dnp no)
		(property "Reference" "D18"
			(at 354.33 137.16 90)
			(effects
				(font
					(size 1.27 1.27)
				)
				(justify right)
			)
		)
		(property "Value" "LED_G_0603_LTST-C190GKT"
			(at 360.68 118.11 0)
			(effects
				(font
					(size 1.27 1.27)
					(thickness 0.15)
				)
				(justify left bottom)
				(hide yes)
			)
		)
		(property "Footprint" "antmicro-footprints:LED_0603_1608Metric_G"
			(at 363.22 118.11 0)
			(effects
				(font
					(size 1.27 1.27)
					(thickness 0.15)
				)
				(justify left bottom)
				(hide yes)
			)
		)
		(property "Datasheet" "https://media.digikey.com/pdf/Data%20Sheets/Lite-On%20PDFs/LTST-C190GKT.pdf"
			(at 365.76 118.11 0)
			(effects
				(font
					(size 1.27 1.27)
					(thickness 0.15)
				)
				(justify left bottom)
				(hide yes)
			)
		)
		(property "Description" "LED, Green, SMD, 0603, 20 mA, 2.1 V, 569 nm"
			(at 353.06 140.97 0)
			(effects
				(font
					(size 1.27 1.27)
				)
				(hide yes)
			)
		)
		(property "MPN" "LTST-C190GKT"
			(at 368.3 118.11 0)
			(effects
				(font
					(size 1.27 1.27)
					(thickness 0.15)
				)
				(justify left bottom)
				(hide yes)
			)
		)
		(property "Manufacturer" "Lite-On"
			(at 370.84 118.11 0)
			(effects
				(font
					(size 1.27 1.27)
					(thickness 0.15)
				)
				(justify left bottom)
				(hide yes)
			)
		)
		(property "Author" "Antmicro"
			(at 373.38 118.11 0)
			(effects
				(font
					(size 1.27 1.27)
					(thickness 0.15)
				)
				(justify left bottom)
				(hide yes)
			)
		)
		(property "License" "Apache-2.0"
			(at 375.92 118.11 0)
			(effects
				(font
					(size 1.27 1.27)
					(thickness 0.15)
				)
				(justify left bottom)
				(hide yes)
			)
		)
		(property "Color" "Green"
			(at 354.33 139.7 90)
			(effects
				(font
					(size 1.27 1.27)
				)
				(justify right)
			)
		)
		(pin "1"
		)
		(pin "2"
		)
		(instances
			(project "thunderbolt-to-10gbe-adapter"
				(path ""
					(reference "D18")
					(unit 1)
				)
			)
		)
	)
	(symbol
		(lib_id "antmicroResistors0402:R_73k2_0402")
		(at 227.33 128.27 90)
		(unit 1)
		(exclude_from_sim no)
		(in_bom yes)
		(on_board yes)
		(dnp no)
		(property "Reference" "R231"
			(at 228.6 124.46 90)
			(effects
				(font
					(size 1.27 1.27)
					(thickness 0.15)
				)
				(justify right)
			)
		)
		(property "Value" "R_73k2_0402"
			(at 240.03 107.95 0)
			(effects
				(font
					(size 1.27 1.27)
					(thickness 0.15)
				)
				(justify left bottom)
				(hide yes)
			)
		)
		(property "Footprint" "antmicro-footprints:R_0402_1005Metric"
			(at 242.57 107.95 0)
			(effects
				(font
					(size 1.27 1.27)
					(thickness 0.15)
				)
				(justify left bottom)
				(hide yes)
			)
		)
		(property "Datasheet" "https://www.bourns.com/docs/product-datasheets/cr.pdf"
			(at 245.11 107.95 0)
			(effects
				(font
					(size 1.27 1.27)
					(thickness 0.15)
				)
				(justify left bottom)
				(hide yes)
			)
		)
		(property "Description" "SMD Chip Resistor"
			(at 227.33 128.27 0)
			(effects
				(font
					(size 1.27 1.27)
				)
				(hide yes)
			)
		)
		(property "MPN" "CR0402-FX-7322GLF"
			(at 247.65 107.95 0)
			(effects
				(font
					(size 1.27 1.27)
					(thickness 0.15)
				)
				(justify left bottom)
				(hide yes)
			)
		)
		(property "Manufacturer" "Bourns"
			(at 250.19 107.95 0)
			(effects
				(font
					(size 1.27 1.27)
					(thickness 0.15)
				)
				(justify left bottom)
				(hide yes)
			)
		)
		(property "License" "Apache-2.0"
			(at 252.73 107.95 0)
			(effects
				(font
					(size 1.27 1.27)
					(thickness 0.15)
				)
				(justify left bottom)
				(hide yes)
			)
		)
		(property "Author" "Antmicro"
			(at 255.27 107.95 0)
			(effects
				(font
					(size 1.27 1.27)
					(thickness 0.15)
				)
				(justify left bottom)
				(hide yes)
			)
		)
		(property "Val" "73k2"
			(at 228.6 127 90)
			(effects
				(font
					(size 1.27 1.27)
					(thickness 0.15)
				)
				(justify right)
			)
		)
		(property "Tolerance" "1%"
			(at 237.49 107.95 0)
			(effects
				(font
					(size 1.27 1.27)
				)
				(justify left bottom)
				(hide yes)
			)
		)
		(pin "2"
		)
		(pin "1"
		)
		(instances
			(project "thunderbolt-to-10gbe-adapter"
				(path ""
					(reference "R231")
					(unit 1)
				)
			)
		)
	)
	(symbol
		(lib_id "antmicropower:GND")
		(at 227.33 139.7 0)
		(unit 1)
		(exclude_from_sim no)
		(in_bom yes)
		(on_board yes)
		(dnp no)
		(property "Reference" "#PWR0482"
			(at 227.33 146.05 0)
			(effects
				(font
					(size 1.27 1.27)
				)
				(justify left bottom)
				(hide yes)
			)
		)
		(property "Value" "GND"
			(at 227.33 143.51 0)
			(effects
				(font
					(size 1.27 1.27)
					(thickness 0.15)
				)
			)
		)
		(property "Footprint" ""
			(at 236.22 147.32 0)
			(effects
				(font
					(size 1.27 1.27)
					(thickness 0.15)
				)
				(justify left bottom)
				(hide yes)
			)
		)
		(property "Datasheet" ""
			(at 236.22 152.4 0)
			(effects
				(font
					(size 1.27 1.27)
					(thickness 0.15)
				)
				(justify left bottom)
				(hide yes)
			)
		)
		(property "Description" ""
			(at 227.33 139.7 0)
			(effects
				(font
					(size 1.27 1.27)
				)
				(hide yes)
			)
		)
		(property "Author" "Antmicro"
			(at 236.22 147.32 0)
			(effects
				(font
					(size 1.27 1.27)
					(thickness 0.15)
				)
				(justify left bottom)
				(hide yes)
			)
		)
		(property "License" "Apache-2.0"
			(at 236.22 149.86 0)
			(effects
				(font
					(size 1.27 1.27)
					(thickness 0.15)
				)
				(justify left bottom)
				(hide yes)
			)
		)
		(pin "1"
		)
		(instances
			(project "thunderbolt-to-10gbe-adapter"
				(path ""
					(reference "#PWR0482")
					(unit 1)
				)
			)
		)
	)
	(symbol
		(lib_id "antmicroResistors0402:R_470R_0402")
		(at 270.51 129.54 90)
		(unit 1)
		(exclude_from_sim no)
		(in_bom yes)
		(on_board yes)
		(dnp no)
		(fields_autoplaced yes)
		(property "Reference" "R233"
			(at 273.05 125.73 90)
			(effects
				(font
					(size 1.27 1.27)
					(thickness 0.15)
				)
				(justify right)
			)
		)
		(property "Value" "R_470R_0402"
			(at 283.21 109.22 0)
			(effects
				(font
					(size 1.27 1.27)
					(thickness 0.15)
				)
				(justify left bottom)
				(hide yes)
			)
		)
		(property "Footprint" "antmicro-footprints:R_0402_1005Metric"
			(at 285.75 109.22 0)
			(effects
				(font
					(size 1.27 1.27)
					(thickness 0.15)
				)
				(justify left bottom)
				(hide yes)
			)
		)
		(property "Datasheet" "https://www.bourns.com/docs/product-datasheets/cr.pdf"
			(at 288.29 109.22 0)
			(effects
				(font
					(size 1.27 1.27)
					(thickness 0.15)
				)
				(justify left bottom)
				(hide yes)
			)
		)
		(property "Description" "SMD Chip Resistor, 470 ohm, ± 1%, 62.5 mW, 0402 [1005 Metric], Thick Film, General Purpose"
			(at 270.51 129.54 0)
			(effects
				(font
					(size 1.27 1.27)
				)
				(hide yes)
			)
		)
		(property "MPN" "CR0402-FX-4700GLF"
			(at 290.83 109.22 0)
			(effects
				(font
					(size 1.27 1.27)
					(thickness 0.15)
				)
				(justify left bottom)
				(hide yes)
			)
		)
		(property "Manufacturer" "Bourns"
			(at 293.37 109.22 0)
			(effects
				(font
					(size 1.27 1.27)
					(thickness 0.15)
				)
				(justify left bottom)
				(hide yes)
			)
		)
		(property "License" "Apache-2.0"
			(at 295.91 109.22 0)
			(effects
				(font
					(size 1.27 1.27)
					(thickness 0.15)
				)
				(justify left bottom)
				(hide yes)
			)
		)
		(property "Author" "Antmicro"
			(at 298.45 109.22 0)
			(effects
				(font
					(size 1.27 1.27)
					(thickness 0.15)
				)
				(justify left bottom)
				(hide yes)
			)
		)
		(property "Val" "470R"
			(at 273.05 128.27 90)
			(effects
				(font
					(size 1.27 1.27)
					(thickness 0.15)
				)
				(justify right)
			)
		)
		(property "Tolerance" "1%"
			(at 280.67 109.22 0)
			(effects
				(font
					(size 1.27 1.27)
				)
				(justify left bottom)
				(hide yes)
			)
		)
		(pin "2"
		)
		(pin "1"
		)
		(instances
			(project "thunderbolt-to-10gbe-adapter"
				(path ""
					(reference "R233")
					(unit 1)
				)
			)
		)
	)
	(symbol
		(lib_id "antmicropower:GND")
		(at 331.47 204.47 0)
		(unit 1)
		(exclude_from_sim no)
		(in_bom yes)
		(on_board yes)
		(dnp no)
		(property "Reference" "#PWR0110"
			(at 340.36 207.01 0)
			(effects
				(font
					(size 1.27 1.27)
					(thickness 0.15)
				)
				(justify left bottom)
				(hide yes)
			)
		)
		(property "Value" "GND"
			(at 331.47 208.28 0)
			(effects
				(font
					(size 1.27 1.27)
					(thickness 0.15)
				)
			)
		)
		(property "Footprint" ""
			(at 340.36 212.09 0)
			(effects
				(font
					(size 1.27 1.27)
					(thickness 0.15)
				)
				(justify left bottom)
				(hide yes)
			)
		)
		(property "Datasheet" ""
			(at 340.36 217.17 0)
			(effects
				(font
					(size 1.27 1.27)
					(thickness 0.15)
				)
				(justify left bottom)
				(hide yes)
			)
		)
		(property "Description" ""
			(at 340.36 219.71 0)
			(effects
				(font
					(size 1.27 1.27)
				)
				(justify left bottom)
				(hide yes)
			)
		)
		(property "Author" "Antmicro"
			(at 340.36 212.09 0)
			(effects
				(font
					(size 1.27 1.27)
					(thickness 0.15)
				)
				(justify left bottom)
				(hide yes)
			)
		)
		(property "License" "Apache-2.0"
			(at 340.36 214.63 0)
			(effects
				(font
					(size 1.27 1.27)
					(thickness 0.15)
				)
				(justify left bottom)
				(hide yes)
			)
		)
		(pin "1"
		)
		(instances
			(project "thunderbolt-to-10gbe-adapter"
				(path ""
					(reference "#PWR0110")
					(unit 1)
				)
			)
		)
	)
	(symbol
		(lib_id "antmicroCapacitorsmisc:C_22u_25V_0805")
		(at 252.73 129.54 90)
		(unit 1)
		(exclude_from_sim no)
		(in_bom yes)
		(on_board yes)
		(dnp no)
		(property "Reference" "C320"
			(at 254.508 124.4601 90)
			(effects
				(font
					(size 1.27 1.27)
					(thickness 0.15)
				)
				(justify right)
			)
		)
		(property "Value" "C_22u_25V_0805"
			(at 262.89 109.22 0)
			(effects
				(font
					(size 1.27 1.27)
					(thickness 0.15)
				)
				(justify left bottom)
				(hide yes)
			)
		)
		(property "Footprint" "antmicro-footprints:C_0805_2012Metric"
			(at 265.43 109.22 0)
			(effects
				(font
					(size 1.27 1.27)
					(thickness 0.15)
				)
				(justify left bottom)
				(hide yes)
			)
		)
		(property "Datasheet" "https://product.samsungsem.com/mlcc/CL21A226MAYNNN.do"
			(at 267.97 109.22 0)
			(effects
				(font
					(size 1.27 1.27)
					(thickness 0.15)
				)
				(justify left bottom)
				(hide yes)
			)
		)
		(property "Description" "SMT Multilayer Ceramic Capacitor, 22uF, +/-20%, 25V, X5R, 0805 [2012 Metric]"
			(at 285.75 109.22 0)
			(effects
				(font
					(size 1.27 1.27)
				)
				(justify left bottom)
				(hide yes)
			)
		)
		(property "MPN" "CL21A226MAYNNNE"
			(at 270.51 109.22 0)
			(effects
				(font
					(size 1.27 1.27)
					(thickness 0.15)
				)
				(justify left bottom)
				(hide yes)
			)
		)
		(property "Manufacturer" "Samsung Electro-Mechanics"
			(at 273.05 109.22 0)
			(effects
				(font
					(size 1.27 1.27)
					(thickness 0.15)
				)
				(justify left bottom)
				(hide yes)
			)
		)
		(property "License" "Apache-2.0"
			(at 275.59 109.22 0)
			(effects
				(font
					(size 1.27 1.27)
					(thickness 0.15)
				)
				(justify left bottom)
				(hide yes)
			)
		)
		(property "Author" "Antmicro"
			(at 278.13 109.22 0)
			(effects
				(font
					(size 1.27 1.27)
					(thickness 0.15)
				)
				(justify left bottom)
				(hide yes)
			)
		)
		(property "Val" "22u"
			(at 254.508 127.0001 90)
			(effects
				(font
					(size 1.27 1.27)
					(thickness 0.15)
				)
				(justify right)
			)
		)
		(property "Voltage" "25V"
			(at 254.508 129.54 90)
			(effects
				(font
					(size 1.27 1.27)
				)
				(justify right)
			)
		)
		(property "Dielectric" "X5R"
			(at 283.21 109.22 0)
			(effects
				(font
					(size 1.27 1.27)
				)
				(justify left bottom)
				(hide yes)
			)
		)
		(property "Public" "False"
			(at 285.75 109.22 0)
			(effects
				(font
					(size 1.27 1.27)
				)
				(justify left bottom)
				(hide yes)
			)
		)
		(pin "2"
		)
		(pin "1"
		)
		(instances
			(project "thunderbolt-to-10gbe-adapter"
				(path ""
					(reference "C320")
					(unit 1)
				)
			)
		)
	)
	(symbol
		(lib_id "antmicroCapacitorsmisc:C_22u_100V_2220")
		(at 120.65 123.19 90)
		(unit 1)
		(exclude_from_sim no)
		(in_bom yes)
		(on_board yes)
		(dnp no)
		(property "Reference" "C313"
			(at 123.19 118.1036 90)
			(effects
				(font
					(size 1.27 1.27)
					(thickness 0.15)
				)
				(justify right)
			)
		)
		(property "Value" "C_22u_100V_2220"
			(at 130.81 102.87 0)
			(effects
				(font
					(size 1.27 1.27)
					(thickness 0.15)
				)
				(justify left bottom)
				(hide yes)
			)
		)
		(property "Footprint" "antmicro-footprints:C_2220_5650Metric"
			(at 133.35 102.87 0)
			(effects
				(font
					(size 1.27 1.27)
					(thickness 0.15)
				)
				(justify left bottom)
				(hide yes)
			)
		)
		(property "Datasheet" "https://product.tdk.com/en/search/capacitor/ceramic/mlcc/info?part_no=C5750X7S2A226M280KB"
			(at 135.89 102.87 0)
			(effects
				(font
					(size 1.27 1.27)
					(thickness 0.15)
				)
				(justify left bottom)
				(hide yes)
			)
		)
		(property "Description" "SMT Multilayer Ceramic Capacitor, 22 µF, 100 V, 2220 [5750 Metric], ± 20%, X7S, C"
			(at 153.67 102.87 0)
			(effects
				(font
					(size 1.27 1.27)
				)
				(justify left bottom)
				(hide yes)
			)
		)
		(property "MPN" "C5750X7S2A226M280KB"
			(at 138.43 102.87 0)
			(effects
				(font
					(size 1.27 1.27)
					(thickness 0.15)
				)
				(justify left bottom)
				(hide yes)
			)
		)
		(property "Manufacturer" "TDK"
			(at 140.97 102.87 0)
			(effects
				(font
					(size 1.27 1.27)
					(thickness 0.15)
				)
				(justify left bottom)
				(hide yes)
			)
		)
		(property "License" "Apache-2.0"
			(at 143.51 102.87 0)
			(effects
				(font
					(size 1.27 1.27)
					(thickness 0.15)
				)
				(justify left bottom)
				(hide yes)
			)
		)
		(property "Author" "Antmicro"
			(at 146.05 102.87 0)
			(effects
				(font
					(size 1.27 1.27)
					(thickness 0.15)
				)
				(justify left bottom)
				(hide yes)
			)
		)
		(property "Val" "22u"
			(at 123.19 120.6436 90)
			(effects
				(font
					(size 1.27 1.27)
					(thickness 0.15)
				)
				(justify right)
			)
		)
		(property "Voltage" "100V"
			(at 123.19 123.1835 90)
			(effects
				(font
					(size 1.27 1.27)
				)
				(justify right)
			)
		)
		(property "Dielectric" "X7S"
			(at 151.13 102.87 0)
			(effects
				(font
					(size 1.27 1.27)
				)
				(justify left bottom)
				(hide yes)
			)
		)
		(property "Public" "False"
			(at 153.67 102.87 0)
			(effects
				(font
					(size 1.27 1.27)
				)
				(justify left bottom)
				(hide yes)
			)
		)
		(pin "1"
		)
		(pin "2"
		)
		(instances
			(project "thunderbolt-to-10gbe-adapter"
				(path ""
					(reference "C313")
					(unit 1)
				)
			)
		)
	)
	(symbol
		(lib_id "antmicropower:GND")
		(at 80.01 134.62 0)
		(unit 1)
		(exclude_from_sim no)
		(in_bom yes)
		(on_board yes)
		(dnp no)
		(property "Reference" "#PWR0471"
			(at 80.01 140.97 0)
			(effects
				(font
					(size 1.27 1.27)
				)
				(justify left bottom)
				(hide yes)
			)
		)
		(property "Value" "GND"
			(at 80.01 138.43 0)
			(effects
				(font
					(size 1.27 1.27)
					(thickness 0.15)
				)
			)
		)
		(property "Footprint" ""
			(at 88.9 142.24 0)
			(effects
				(font
					(size 1.27 1.27)
					(thickness 0.15)
				)
				(justify left bottom)
				(hide yes)
			)
		)
		(property "Datasheet" ""
			(at 88.9 147.32 0)
			(effects
				(font
					(size 1.27 1.27)
					(thickness 0.15)
				)
				(justify left bottom)
				(hide yes)
			)
		)
		(property "Description" ""
			(at 80.01 134.62 0)
			(effects
				(font
					(size 1.27 1.27)
				)
				(hide yes)
			)
		)
		(property "Author" "Antmicro"
			(at 88.9 142.24 0)
			(effects
				(font
					(size 1.27 1.27)
					(thickness 0.15)
				)
				(justify left bottom)
				(hide yes)
			)
		)
		(property "License" "Apache-2.0"
			(at 88.9 144.78 0)
			(effects
				(font
					(size 1.27 1.27)
					(thickness 0.15)
				)
				(justify left bottom)
				(hide yes)
			)
		)
		(pin "1"
		)
		(instances
			(project "thunderbolt-to-10gbe-adapter"
				(path ""
					(reference "#PWR0471")
					(unit 1)
				)
			)
		)
	)
	(symbol
		(lib_id "antmicroResistors0402:R_470R_0402")
		(at 353.06 134.62 90)
		(unit 1)
		(exclude_from_sim no)
		(in_bom yes)
		(on_board yes)
		(dnp no)
		(fields_autoplaced yes)
		(property "Reference" "R237"
			(at 355.6 130.81 90)
			(effects
				(font
					(size 1.27 1.27)
					(thickness 0.15)
				)
				(justify right)
			)
		)
		(property "Value" "R_470R_0402"
			(at 365.76 114.3 0)
			(effects
				(font
					(size 1.27 1.27)
					(thickness 0.15)
				)
				(justify left bottom)
				(hide yes)
			)
		)
		(property "Footprint" "antmicro-footprints:R_0402_1005Metric"
			(at 368.3 114.3 0)
			(effects
				(font
					(size 1.27 1.27)
					(thickness 0.15)
				)
				(justify left bottom)
				(hide yes)
			)
		)
		(property "Datasheet" "https://www.bourns.com/docs/product-datasheets/cr.pdf"
			(at 370.84 114.3 0)
			(effects
				(font
					(size 1.27 1.27)
					(thickness 0.15)
				)
				(justify left bottom)
				(hide yes)
			)
		)
		(property "Description" "SMD Chip Resistor, 470 ohm, ± 1%, 62.5 mW, 0402 [1005 Metric], Thick Film, General Purpose"
			(at 353.06 134.62 0)
			(effects
				(font
					(size 1.27 1.27)
				)
				(hide yes)
			)
		)
		(property "MPN" "CR0402-FX-4700GLF"
			(at 373.38 114.3 0)
			(effects
				(font
					(size 1.27 1.27)
					(thickness 0.15)
				)
				(justify left bottom)
				(hide yes)
			)
		)
		(property "Manufacturer" "Bourns"
			(at 375.92 114.3 0)
			(effects
				(font
					(size 1.27 1.27)
					(thickness 0.15)
				)
				(justify left bottom)
				(hide yes)
			)
		)
		(property "License" "Apache-2.0"
			(at 378.46 114.3 0)
			(effects
				(font
					(size 1.27 1.27)
					(thickness 0.15)
				)
				(justify left bottom)
				(hide yes)
			)
		)
		(property "Author" "Antmicro"
			(at 381 114.3 0)
			(effects
				(font
					(size 1.27 1.27)
					(thickness 0.15)
				)
				(justify left bottom)
				(hide yes)
			)
		)
		(property "Val" "470R"
			(at 355.6 133.35 90)
			(effects
				(font
					(size 1.27 1.27)
					(thickness 0.15)
				)
				(justify right)
			)
		)
		(property "Tolerance" "1%"
			(at 363.22 114.3 0)
			(effects
				(font
					(size 1.27 1.27)
				)
				(justify left bottom)
				(hide yes)
			)
		)
		(pin "2"
		)
		(pin "1"
		)
		(instances
			(project "thunderbolt-to-10gbe-adapter"
				(path ""
					(reference "R237")
					(unit 1)
				)
			)
		)
	)
	(symbol
		(lib_id "antmicropower:GND")
		(at 337.82 175.26 0)
		(unit 1)
		(exclude_from_sim no)
		(in_bom yes)
		(on_board yes)
		(dnp no)
		(fields_autoplaced yes)
		(property "Reference" "#PWR0494"
			(at 337.82 181.61 0)
			(effects
				(font
					(size 1.27 1.27)
				)
				(hide yes)
			)
		)
		(property "Value" "GND"
			(at 335.915 179.705 0)
			(effects
				(font
					(size 1.27 1.27)
					(thickness 0.15)
				)
				(justify left bottom)
			)
		)
		(property "Footprint" ""
			(at 346.71 182.88 0)
			(effects
				(font
					(size 1.27 1.27)
					(thickness 0.15)
				)
				(justify left bottom)
				(hide yes)
			)
		)
		(property "Datasheet" ""
			(at 346.71 187.96 0)
			(effects
				(font
					(size 1.27 1.27)
					(thickness 0.15)
				)
				(justify left bottom)
				(hide yes)
			)
		)
		(property "Description" ""
			(at 337.82 175.26 0)
			(effects
				(font
					(size 1.27 1.27)
				)
			)
		)
		(property "Author" "Antmicro"
			(at 346.71 180.34 0)
			(effects
				(font
					(size 1.27 1.27)
					(thickness 0.15)
				)
				(justify left bottom)
				(hide yes)
			)
		)
		(property "License" "Apache-2.0"
			(at 346.71 182.88 0)
			(effects
				(font
					(size 1.27 1.27)
					(thickness 0.15)
				)
				(justify left bottom)
				(hide yes)
			)
		)
		(pin "1"
		)
		(instances
			(project "thunderbolt-to-10gbe-adapter"
				(path ""
					(reference "#PWR0494")
					(unit 1)
				)
			)
		)
	)
	(symbol
		(lib_id "antmicropower:+5V")
		(at 309.88 166.37 0)
		(unit 1)
		(exclude_from_sim no)
		(in_bom yes)
		(on_board yes)
		(dnp no)
		(property "Reference" "#PWR0490"
			(at 325.12 168.91 0)
			(effects
				(font
					(size 1.27 1.27)
					(thickness 0.15)
				)
				(justify left bottom)
				(hide yes)
			)
		)
		(property "Value" "+5V_USB"
			(at 309.88 162.56 0)
			(effects
				(font
					(size 1.27 1.27)
					(thickness 0.15)
				)
			)
		)
		(property "Footprint" ""
			(at 325.12 173.99 0)
			(effects
				(font
					(size 1.27 1.27)
					(thickness 0.15)
				)
				(justify left bottom)
				(hide yes)
			)
		)
		(property "Datasheet" ""
			(at 325.12 176.53 0)
			(effects
				(font
					(size 1.27 1.27)
					(thickness 0.15)
				)
				(justify left bottom)
				(hide yes)
			)
		)
		(property "Description" ""
			(at 325.12 179.07 0)
			(effects
				(font
					(size 1.27 1.27)
				)
				(justify left bottom)
				(hide yes)
			)
		)
		(property "Author" "Antmicro"
			(at 325.12 173.99 0)
			(effects
				(font
					(size 1.27 1.27)
					(thickness 0.15)
				)
				(justify left bottom)
				(hide yes)
			)
		)
		(property "License" "Apache-2.0"
			(at 325.12 176.53 0)
			(effects
				(font
					(size 1.27 1.27)
					(thickness 0.15)
				)
				(justify left bottom)
				(hide yes)
			)
		)
		(pin "1"
		)
		(instances
			(project "thunderbolt-to-10gbe-adapter"
				(path ""
					(reference "#PWR0490")
					(unit 1)
				)
			)
		)
	)
	(symbol
		(lib_id "antmicroResistors0402:R_20k_0402")
		(at 101.6 134.62 90)
		(unit 1)
		(exclude_from_sim no)
		(in_bom yes)
		(on_board yes)
		(dnp no)
		(property "Reference" "R226"
			(at 102.87 130.81 90)
			(effects
				(font
					(size 1.27 1.27)
					(thickness 0.15)
				)
				(justify right)
			)
		)
		(property "Value" "R_20k_0402"
			(at 114.3 114.3 0)
			(effects
				(font
					(size 1.27 1.27)
					(thickness 0.15)
				)
				(justify left bottom)
				(hide yes)
			)
		)
		(property "Footprint" "antmicro-footprints:R_0402_1005Metric"
			(at 116.84 114.3 0)
			(effects
				(font
					(size 1.27 1.27)
					(thickness 0.15)
				)
				(justify left bottom)
				(hide yes)
			)
		)
		(property "Datasheet" "https://www.bourns.com/docs/product-datasheets/cr.pdf"
			(at 119.38 114.3 0)
			(effects
				(font
					(size 1.27 1.27)
					(thickness 0.15)
				)
				(justify left bottom)
				(hide yes)
			)
		)
		(property "Description" "SMD Chip Resistor, 20 kohm, ± 1%, 62.5 mW, 0402 [1005 Metric], Thick Film, General Purpose"
			(at 132.08 114.3 0)
			(effects
				(font
					(size 1.27 1.27)
				)
				(justify left bottom)
				(hide yes)
			)
		)
		(property "MPN" "CR0402-FX-2002GLF"
			(at 121.92 114.3 0)
			(effects
				(font
					(size 1.27 1.27)
					(thickness 0.15)
				)
				(justify left bottom)
				(hide yes)
			)
		)
		(property "Manufacturer" "Bourns"
			(at 124.46 114.3 0)
			(effects
				(font
					(size 1.27 1.27)
					(thickness 0.15)
				)
				(justify left bottom)
				(hide yes)
			)
		)
		(property "License" "Apache-2.0"
			(at 127 114.3 0)
			(effects
				(font
					(size 1.27 1.27)
					(thickness 0.15)
				)
				(justify left bottom)
				(hide yes)
			)
		)
		(property "Author" "Antmicro"
			(at 129.54 114.3 0)
			(effects
				(font
					(size 1.27 1.27)
					(thickness 0.15)
				)
				(justify left bottom)
				(hide yes)
			)
		)
		(property "Val" "20k"
			(at 102.87 133.35 90)
			(effects
				(font
					(size 1.27 1.27)
					(thickness 0.15)
				)
				(justify right)
			)
		)
		(property "Tolerance" "1%"
			(at 111.76 114.3 0)
			(effects
				(font
					(size 1.27 1.27)
				)
				(justify left bottom)
				(hide yes)
			)
		)
		(pin "1"
		)
		(pin "2"
		)
		(instances
			(project "thunderbolt-to-10gbe-adapter"
				(path ""
					(reference "R226")
					(unit 1)
				)
			)
		)
	)
	(symbol
		(lib_id "antmicropower:GND")
		(at 304.8 147.32 0)
		(unit 1)
		(exclude_from_sim no)
		(in_bom yes)
		(on_board yes)
		(dnp no)
		(fields_autoplaced yes)
		(property "Reference" "#PWR0489"
			(at 304.8 153.67 0)
			(effects
				(font
					(size 1.27 1.27)
				)
				(hide yes)
			)
		)
		(property "Value" "GND"
			(at 302.895 151.765 0)
			(effects
				(font
					(size 1.27 1.27)
					(thickness 0.15)
				)
				(justify left bottom)
			)
		)
		(property "Footprint" ""
			(at 313.69 154.94 0)
			(effects
				(font
					(size 1.27 1.27)
					(thickness 0.15)
				)
				(justify left bottom)
				(hide yes)
			)
		)
		(property "Datasheet" ""
			(at 313.69 160.02 0)
			(effects
				(font
					(size 1.27 1.27)
					(thickness 0.15)
				)
				(justify left bottom)
				(hide yes)
			)
		)
		(property "Description" ""
			(at 304.8 147.32 0)
			(effects
				(font
					(size 1.27 1.27)
				)
			)
		)
		(property "Author" "Antmicro"
			(at 313.69 152.4 0)
			(effects
				(font
					(size 1.27 1.27)
					(thickness 0.15)
				)
				(justify left bottom)
				(hide yes)
			)
		)
		(property "License" "Apache-2.0"
			(at 313.69 154.94 0)
			(effects
				(font
					(size 1.27 1.27)
					(thickness 0.15)
				)
				(justify left bottom)
				(hide yes)
			)
		)
		(pin "1"
		)
		(instances
			(project "thunderbolt-to-10gbe-adapter"
				(path ""
					(reference "#PWR0489")
					(unit 1)
				)
			)
		)
	)
	(symbol
		(lib_id "antmicroTestPoints:TP_0.75mm_SMD")
		(at 332.74 198.12 0)
		(unit 1)
		(exclude_from_sim no)
		(in_bom no)
		(on_board yes)
		(dnp no)
		(fields_autoplaced yes)
		(property "Reference" "TP38"
			(at 337.82 198.12 0)
			(effects
				(font
					(size 1.27 1.27)
					(thickness 0.15)
				)
				(justify left)
			)
		)
		(property "Value" "TP_0.75mm_SMD"
			(at 342.9 201.93 0)
			(effects
				(font
					(size 1.27 1.27)
					(thickness 0.15)
				)
				(justify left bottom)
				(hide yes)
			)
		)
		(property "Footprint" "antmicro-footprints:TP_SMD_0.75mm"
			(at 342.9 204.47 0)
			(effects
				(font
					(size 1.27 1.27)
					(thickness 0.15)
				)
				(justify left bottom)
				(hide yes)
			)
		)
		(property "Datasheet" ""
			(at 350.52 210.82 0)
			(effects
				(font
					(size 1.27 1.27)
					(thickness 0.15)
				)
				(justify left bottom)
				(hide yes)
			)
		)
		(property "Description" "SMT test point"
			(at 343.535 212.09 0)
			(effects
				(font
					(size 1.27 1.27)
				)
				(justify left bottom)
				(hide yes)
			)
		)
		(property "MPN" ""
			(at 343.535 209.55 0)
			(effects
				(font
					(size 1.27 1.27)
					(thickness 0.15)
				)
				(justify left bottom)
				(hide yes)
			)
		)
		(property "Manufacturer" ""
			(at 343.535 204.47 0)
			(effects
				(font
					(size 1.27 1.27)
					(thickness 0.15)
				)
				(justify left bottom)
				(hide yes)
			)
		)
		(property "Author" "Antmicro"
			(at 342.9 207.01 0)
			(effects
				(font
					(size 1.27 1.27)
					(thickness 0.15)
				)
				(justify left bottom)
				(hide yes)
			)
		)
		(property "License" "Apache-2.0"
			(at 342.9 209.55 0)
			(effects
				(font
					(size 1.27 1.27)
					(thickness 0.15)
				)
				(justify left bottom)
				(hide yes)
			)
		)
		(pin "1"
		)
		(instances
			(project "thunderbolt-to-10gbe-adapter"
				(path ""
					(reference "TP38")
					(unit 1)
				)
			)
		)
	)
	(symbol
		(lib_id "antmicropower:GND")
		(at 110.49 124.46 0)
		(unit 1)
		(exclude_from_sim no)
		(in_bom yes)
		(on_board yes)
		(dnp no)
		(fields_autoplaced yes)
		(property "Reference" "#PWR0473"
			(at 110.49 130.81 0)
			(effects
				(font
					(size 1.27 1.27)
				)
				(justify left bottom)
				(hide yes)
			)
		)
		(property "Value" "GND"
			(at 110.49 128.27 0)
			(effects
				(font
					(size 1.27 1.27)
					(thickness 0.15)
				)
			)
		)
		(property "Footprint" ""
			(at 119.38 132.08 0)
			(effects
				(font
					(size 1.27 1.27)
					(thickness 0.15)
				)
				(justify left bottom)
				(hide yes)
			)
		)
		(property "Datasheet" ""
			(at 119.38 137.16 0)
			(effects
				(font
					(size 1.27 1.27)
					(thickness 0.15)
				)
				(justify left bottom)
				(hide yes)
			)
		)
		(property "Description" ""
			(at 110.49 124.46 0)
			(effects
				(font
					(size 1.27 1.27)
				)
				(hide yes)
			)
		)
		(property "Author" "Antmicro"
			(at 119.38 132.08 0)
			(effects
				(font
					(size 1.27 1.27)
					(thickness 0.15)
				)
				(justify left bottom)
				(hide yes)
			)
		)
		(property "License" "Apache-2.0"
			(at 119.38 134.62 0)
			(effects
				(font
					(size 1.27 1.27)
					(thickness 0.15)
				)
				(justify left bottom)
				(hide yes)
			)
		)
		(pin "1"
		)
		(instances
			(project "thunderbolt-to-10gbe-adapter"
				(path ""
					(reference "#PWR0473")
					(unit 1)
				)
			)
		)
	)
	(symbol
		(lib_id "antmicropower:GND")
		(at 199.39 139.7 0)
		(unit 1)
		(exclude_from_sim no)
		(in_bom yes)
		(on_board yes)
		(dnp no)
		(property "Reference" "#PWR0481"
			(at 199.39 146.05 0)
			(effects
				(font
					(size 1.27 1.27)
				)
				(justify left bottom)
				(hide yes)
			)
		)
		(property "Value" "GND"
			(at 199.39 143.51 0)
			(effects
				(font
					(size 1.27 1.27)
					(thickness 0.15)
				)
			)
		)
		(property "Footprint" ""
			(at 208.28 147.32 0)
			(effects
				(font
					(size 1.27 1.27)
					(thickness 0.15)
				)
				(justify left bottom)
				(hide yes)
			)
		)
		(property "Datasheet" ""
			(at 208.28 152.4 0)
			(effects
				(font
					(size 1.27 1.27)
					(thickness 0.15)
				)
				(justify left bottom)
				(hide yes)
			)
		)
		(property "Description" ""
			(at 199.39 139.7 0)
			(effects
				(font
					(size 1.27 1.27)
				)
				(hide yes)
			)
		)
		(property "Author" "Antmicro"
			(at 208.28 147.32 0)
			(effects
				(font
					(size 1.27 1.27)
					(thickness 0.15)
				)
				(justify left bottom)
				(hide yes)
			)
		)
		(property "License" "Apache-2.0"
			(at 208.28 149.86 0)
			(effects
				(font
					(size 1.27 1.27)
					(thickness 0.15)
				)
				(justify left bottom)
				(hide yes)
			)
		)
		(pin "1"
		)
		(instances
			(project "thunderbolt-to-10gbe-adapter"
				(path ""
					(reference "#PWR0481")
					(unit 1)
				)
			)
		)
	)
	(symbol
		(lib_id "antmicropower:GND")
		(at 68.58 151.13 0)
		(unit 1)
		(exclude_from_sim no)
		(in_bom yes)
		(on_board yes)
		(dnp no)
		(property "Reference" "#PWR0470"
			(at 68.58 157.48 0)
			(effects
				(font
					(size 1.27 1.27)
				)
				(justify left bottom)
				(hide yes)
			)
		)
		(property "Value" "GND"
			(at 68.58 154.94 0)
			(effects
				(font
					(size 1.27 1.27)
					(thickness 0.15)
				)
			)
		)
		(property "Footprint" ""
			(at 77.47 158.75 0)
			(effects
				(font
					(size 1.27 1.27)
					(thickness 0.15)
				)
				(justify left bottom)
				(hide yes)
			)
		)
		(property "Datasheet" ""
			(at 77.47 163.83 0)
			(effects
				(font
					(size 1.27 1.27)
					(thickness 0.15)
				)
				(justify left bottom)
				(hide yes)
			)
		)
		(property "Description" ""
			(at 68.58 151.13 0)
			(effects
				(font
					(size 1.27 1.27)
				)
				(hide yes)
			)
		)
		(property "Author" "Antmicro"
			(at 77.47 158.75 0)
			(effects
				(font
					(size 1.27 1.27)
					(thickness 0.15)
				)
				(justify left bottom)
				(hide yes)
			)
		)
		(property "License" "Apache-2.0"
			(at 77.47 161.29 0)
			(effects
				(font
					(size 1.27 1.27)
					(thickness 0.15)
				)
				(justify left bottom)
				(hide yes)
			)
		)
		(pin "1"
		)
		(instances
			(project "thunderbolt-to-10gbe-adapter"
				(path ""
					(reference "#PWR0470")
					(unit 1)
				)
			)
		)
	)
	(symbol
		(lib_id "antmicropower:GND")
		(at 363.22 176.53 0)
		(unit 1)
		(exclude_from_sim no)
		(in_bom yes)
		(on_board yes)
		(dnp no)
		(property "Reference" "#PWR0498"
			(at 363.22 182.88 0)
			(effects
				(font
					(size 1.27 1.27)
				)
				(hide yes)
			)
		)
		(property "Value" "GND"
			(at 363.22 180.34 0)
			(effects
				(font
					(size 1.27 1.27)
				)
			)
		)
		(property "Footprint" ""
			(at 363.22 176.53 0)
			(effects
				(font
					(size 1.27 1.27)
				)
				(hide yes)
			)
		)
		(property "Datasheet" ""
			(at 363.22 176.53 0)
			(effects
				(font
					(size 1.27 1.27)
				)
				(hide yes)
			)
		)
		(property "Description" ""
			(at 363.22 176.53 0)
			(effects
				(font
					(size 1.27 1.27)
				)
				(hide yes)
			)
		)
		(property "Author" "Antmicro"
			(at 372.11 184.15 0)
			(effects
				(font
					(size 1.27 1.27)
					(thickness 0.15)
				)
				(justify left bottom)
				(hide yes)
			)
		)
		(property "License" "Apache-2.0"
			(at 372.11 186.69 0)
			(effects
				(font
					(size 1.27 1.27)
					(thickness 0.15)
				)
				(justify left bottom)
				(hide yes)
			)
		)
		(pin "1"
		)
		(instances
			(project "thunderbolt-to-10gbe-adapter"
				(path ""
					(reference "#PWR0498")
					(unit 1)
				)
			)
		)
	)
	(symbol
		(lib_id "antmicroResistors0402:R_200k_0402")
		(at 142.24 140.97 90)
		(unit 1)
		(exclude_from_sim no)
		(in_bom yes)
		(on_board yes)
		(dnp no)
		(property "Reference" "R229"
			(at 143.51 137.16 90)
			(effects
				(font
					(size 1.27 1.27)
					(thickness 0.15)
				)
				(justify right)
			)
		)
		(property "Value" "R_200k_0402"
			(at 154.94 120.65 0)
			(effects
				(font
					(size 1.27 1.27)
					(thickness 0.15)
				)
				(justify left bottom)
				(hide yes)
			)
		)
		(property "Footprint" "antmicro-footprints:R_0402_1005Metric"
			(at 157.48 120.65 0)
			(effects
				(font
					(size 1.27 1.27)
					(thickness 0.15)
				)
				(justify left bottom)
				(hide yes)
			)
		)
		(property "Datasheet" "https://www.bourns.com/docs/product-datasheets/cr.pdf"
			(at 160.02 120.65 0)
			(effects
				(font
					(size 1.27 1.27)
					(thickness 0.15)
				)
				(justify left bottom)
				(hide yes)
			)
		)
		(property "Description" "SMD Chip Resistor, 200 kohm, ± 1%, 62.5 mW, 0402 [1005 Metric], Thick Film, General Purpose"
			(at 172.72 120.65 0)
			(effects
				(font
					(size 1.27 1.27)
				)
				(justify left bottom)
				(hide yes)
			)
		)
		(property "MPN" "CR0402-FX-2003GLF"
			(at 162.56 120.65 0)
			(effects
				(font
					(size 1.27 1.27)
					(thickness 0.15)
				)
				(justify left bottom)
				(hide yes)
			)
		)
		(property "Manufacturer" "Bourns"
			(at 165.1 120.65 0)
			(effects
				(font
					(size 1.27 1.27)
					(thickness 0.15)
				)
				(justify left bottom)
				(hide yes)
			)
		)
		(property "License" "Apache-2.0"
			(at 167.64 120.65 0)
			(effects
				(font
					(size 1.27 1.27)
					(thickness 0.15)
				)
				(justify left bottom)
				(hide yes)
			)
		)
		(property "Author" "Antmicro"
			(at 170.18 120.65 0)
			(effects
				(font
					(size 1.27 1.27)
					(thickness 0.15)
				)
				(justify left bottom)
				(hide yes)
			)
		)
		(property "Val" "200k"
			(at 143.51 139.7 90)
			(effects
				(font
					(size 1.27 1.27)
					(thickness 0.15)
				)
				(justify right)
			)
		)
		(property "Tolerance" "1%"
			(at 152.4 120.65 0)
			(effects
				(font
					(size 1.27 1.27)
				)
				(justify left bottom)
				(hide yes)
			)
		)
		(pin "2"
		)
		(pin "1"
		)
		(instances
			(project "thunderbolt-to-10gbe-adapter"
				(path ""
					(reference "R229")
					(unit 1)
				)
			)
		)
	)
	(symbol
		(lib_id "antmicropower:GND")
		(at 346.71 175.26 0)
		(unit 1)
		(exclude_from_sim no)
		(in_bom yes)
		(on_board yes)
		(dnp no)
		(property "Reference" "#PWR0496"
			(at 346.71 181.61 0)
			(effects
				(font
					(size 1.27 1.27)
				)
				(justify left bottom)
				(hide yes)
			)
		)
		(property "Value" "GND"
			(at 346.71 179.07 0)
			(effects
				(font
					(size 1.27 1.27)
					(thickness 0.15)
				)
			)
		)
		(property "Footprint" ""
			(at 355.6 182.88 0)
			(effects
				(font
					(size 1.27 1.27)
					(thickness 0.15)
				)
				(justify left bottom)
				(hide yes)
			)
		)
		(property "Datasheet" ""
			(at 355.6 187.96 0)
			(effects
				(font
					(size 1.27 1.27)
					(thickness 0.15)
				)
				(justify left bottom)
				(hide yes)
			)
		)
		(property "Description" ""
			(at 346.71 175.26 0)
			(effects
				(font
					(size 1.27 1.27)
				)
				(hide yes)
			)
		)
		(property "Author" "Antmicro"
			(at 355.6 182.88 0)
			(effects
				(font
					(size 1.27 1.27)
					(thickness 0.15)
				)
				(justify left bottom)
				(hide yes)
			)
		)
		(property "License" "Apache-2.0"
			(at 355.6 185.42 0)
			(effects
				(font
					(size 1.27 1.27)
					(thickness 0.15)
				)
				(justify left bottom)
				(hide yes)
			)
		)
		(pin "1"
		)
		(instances
			(project "thunderbolt-to-10gbe-adapter"
				(path ""
					(reference "#PWR0496")
					(unit 1)
				)
			)
		)
	)
	(symbol
		(lib_id "antmicropower:PWR_FLAG")
		(at 87.63 115.57 0)
		(unit 1)
		(exclude_from_sim no)
		(in_bom yes)
		(on_board yes)
		(dnp no)
		(property "Reference" "#FLG035"
			(at 87.63 113.665 0)
			(effects
				(font
					(size 1.27 1.27)
				)
				(hide yes)
			)
		)
		(property "Value" "PWR_FLAG"
			(at 87.63 111.76 0)
			(effects
				(font
					(size 1.27 1.27)
				)
			)
		)
		(property "Footprint" ""
			(at 87.63 115.57 0)
			(effects
				(font
					(size 1.27 1.27)
				)
				(hide yes)
			)
		)
		(property "Datasheet" ""
			(at 87.63 115.57 0)
			(effects
				(font
					(size 1.27 1.27)
				)
				(hide yes)
			)
		)
		(property "Description" ""
			(at 87.63 118.11 0)
			(effects
				(font
					(size 1.27 1.27)
				)
				(justify left bottom)
				(hide yes)
			)
		)
		(pin "1"
		)
		(instances
			(project "thunderbolt-to-10gbe-adapter"
				(path ""
					(reference "#FLG035")
					(unit 1)
				)
			)
		)
	)
	(symbol
		(lib_id "antmicropower:+5V")
		(at 331.47 194.31 0)
		(unit 1)
		(exclude_from_sim no)
		(in_bom yes)
		(on_board yes)
		(dnp no)
		(property "Reference" "#PWR0492"
			(at 346.71 196.85 0)
			(effects
				(font
					(size 1.27 1.27)
					(thickness 0.15)
				)
				(justify left bottom)
				(hide yes)
			)
		)
		(property "Value" "+5V"
			(at 331.47 190.5 0)
			(effects
				(font
					(size 1.27 1.27)
					(thickness 0.15)
				)
			)
		)
		(property "Footprint" ""
			(at 346.71 201.93 0)
			(effects
				(font
					(size 1.27 1.27)
					(thickness 0.15)
				)
				(justify left bottom)
				(hide yes)
			)
		)
		(property "Datasheet" ""
			(at 346.71 204.47 0)
			(effects
				(font
					(size 1.27 1.27)
					(thickness 0.15)
				)
				(justify left bottom)
				(hide yes)
			)
		)
		(property "Description" ""
			(at 346.71 207.01 0)
			(effects
				(font
					(size 1.27 1.27)
				)
				(justify left bottom)
				(hide yes)
			)
		)
		(property "Author" "Antmicro"
			(at 346.71 201.93 0)
			(effects
				(font
					(size 1.27 1.27)
					(thickness 0.15)
				)
				(justify left bottom)
				(hide yes)
			)
		)
		(property "License" "Apache-2.0"
			(at 346.71 204.47 0)
			(effects
				(font
					(size 1.27 1.27)
					(thickness 0.15)
				)
				(justify left bottom)
				(hide yes)
			)
		)
		(pin "1"
		)
		(instances
			(project "thunderbolt-to-10gbe-adapter"
				(path ""
					(reference "#PWR0492")
					(unit 1)
				)
			)
		)
	)
	(symbol
		(lib_id "antmicroCapacitors0402:C_1u_25V_0402")
		(at 337.82 128.27 90)
		(unit 1)
		(exclude_from_sim no)
		(in_bom yes)
		(on_board yes)
		(dnp no)
		(property "Reference" "C323"
			(at 340.106 124.46 90)
			(effects
				(font
					(size 1.27 1.27)
					(thickness 0.15)
				)
				(justify right)
			)
		)
		(property "Value" "C_1u_25V_0402"
			(at 347.98 107.95 0)
			(effects
				(font
					(size 1.27 1.27)
					(thickness 0.15)
				)
				(justify left bottom)
				(hide yes)
			)
		)
		(property "Footprint" "antmicro-footprints:C_0402_1005Metric"
			(at 350.52 107.95 0)
			(effects
				(font
					(size 1.27 1.27)
					(thickness 0.15)
				)
				(justify left bottom)
				(hide yes)
			)
		)
		(property "Datasheet" "https://www.murata.com/products/productdetail?partno=GRM155R61E105KE11%23"
			(at 353.06 107.95 0)
			(effects
				(font
					(size 1.27 1.27)
					(thickness 0.15)
				)
				(justify left bottom)
				(hide yes)
			)
		)
		(property "Description" "SMD Multilayer Ceramic Capacitor, 1 µF, 25 V, 0402 [1005 Metric], ± 10%, X5R, GRM Series"
			(at 337.82 128.27 0)
			(effects
				(font
					(size 1.27 1.27)
				)
				(hide yes)
			)
		)
		(property "MPN" "GRM155R61E105KE11J"
			(at 355.6 107.95 0)
			(effects
				(font
					(size 1.27 1.27)
					(thickness 0.15)
				)
				(justify left bottom)
				(hide yes)
			)
		)
		(property "Manufacturer" "Murata"
			(at 358.14 107.95 0)
			(effects
				(font
					(size 1.27 1.27)
					(thickness 0.15)
				)
				(justify left bottom)
				(hide yes)
			)
		)
		(property "License" "Apache-2.0"
			(at 360.68 107.95 0)
			(effects
				(font
					(size 1.27 1.27)
					(thickness 0.15)
				)
				(justify left bottom)
				(hide yes)
			)
		)
		(property "Author" "Antmicro"
			(at 363.22 107.95 0)
			(effects
				(font
					(size 1.27 1.27)
					(thickness 0.15)
				)
				(justify left bottom)
				(hide yes)
			)
		)
		(property "Val" "1u"
			(at 340.106 127 90)
			(effects
				(font
					(size 1.27 1.27)
					(thickness 0.15)
				)
				(justify right)
			)
		)
		(property "Voltage" "25V"
			(at 365.76 107.95 0)
			(effects
				(font
					(size 1.27 1.27)
				)
				(justify left bottom)
				(hide yes)
			)
		)
		(property "Dielectric" "X5R"
			(at 368.3 107.95 0)
			(effects
				(font
					(size 1.27 1.27)
				)
				(justify left bottom)
				(hide yes)
			)
		)
		(pin "2"
		)
		(pin "1"
		)
		(instances
			(project "thunderbolt-to-10gbe-adapter"
				(path ""
					(reference "C323")
					(unit 1)
				)
			)
		)
	)
	(symbol
		(lib_id "antmicroCapacitorspol:C_Pol_330u_6.3V_KEMET-T520-B")
		(at 363.22 170.18 270)
		(unit 1)
		(exclude_from_sim no)
		(in_bom yes)
		(on_board yes)
		(dnp yes)
		(fields_autoplaced yes)
		(property "Reference" "C325"
			(at 365.76 170.9166 90)
			(effects
				(font
					(size 1.27 1.27)
					(thickness 0.15)
				)
				(justify left)
			)
		)
		(property "Value" "C_Pol_330u_6.3V_KEMET-T520-B"
			(at 360.68 184.15 0)
			(effects
				(font
					(size 1.27 1.27)
					(thickness 0.15)
				)
				(justify left bottom)
				(hide yes)
			)
		)
		(property "Footprint" "antmicro-footprints:C_Pol_EIA-B"
			(at 355.6 184.15 0)
			(effects
				(font
					(size 1.27 1.27)
					(thickness 0.15)
				)
				(justify left bottom)
				(hide yes)
			)
		)
		(property "Datasheet" "https://www.kemet.com/en/us/capacitors/product/T520B337M006ATE040.html"
			(at 353.06 184.15 0)
			(effects
				(font
					(size 1.27 1.27)
					(thickness 0.15)
				)
				(justify left bottom)
				(hide yes)
			)
		)
		(property "Description" "Tantalum Polymer Capacitor, KO-CAP®, 330 µF, ± 20%, 6.3 V, B, 0.04 ohm, 1411 [3528 Metric]"
			(at 363.22 170.18 0)
			(effects
				(font
					(size 1.27 1.27)
				)
				(hide yes)
			)
		)
		(property "Val" "330u"
			(at 365.76 173.4566 90)
			(effects
				(font
					(size 1.27 1.27)
					(thickness 0.15)
				)
				(justify left)
			)
		)
		(property "MPN" "T520B337M006ATE040"
			(at 350.52 184.15 0)
			(effects
				(font
					(size 1.27 1.27)
					(thickness 0.15)
				)
				(justify left bottom)
				(hide yes)
			)
		)
		(property "Manufacturer" "KEMET"
			(at 347.98 184.15 0)
			(effects
				(font
					(size 1.27 1.27)
					(thickness 0.15)
				)
				(justify left bottom)
				(hide yes)
			)
		)
		(property "License" "Apache-2.0"
			(at 345.44 184.15 0)
			(effects
				(font
					(size 1.27 1.27)
					(thickness 0.15)
				)
				(justify left bottom)
				(hide yes)
			)
		)
		(property "Author" "Antmicro"
			(at 342.9 184.15 0)
			(effects
				(font
					(size 1.27 1.27)
					(thickness 0.15)
				)
				(justify left bottom)
				(hide yes)
			)
		)
		(property "Voltage" "6.3V"
			(at 340.36 184.15 0)
			(effects
				(font
					(size 1.27 1.27)
				)
				(justify left bottom)
				(hide yes)
			)
		)
		(property "Dielectric" "template_dielectric"
			(at 337.82 184.15 0)
			(effects
				(font
					(size 1.27 1.27)
				)
				(justify left bottom)
				(hide yes)
			)
		)
		(pin "1"
		)
		(pin "2"
		)
		(instances
			(project "thunderbolt-to-10gbe-adapter"
				(path ""
					(reference "C325")
					(unit 1)
				)
			)
		)
	)
	(symbol
		(lib_id "antmicroTVSDiodes:PTVS26VS1UR,115")
		(at 80.01 123.19 270)
		(unit 1)
		(exclude_from_sim no)
		(in_bom yes)
		(on_board yes)
		(dnp no)
		(fields_autoplaced yes)
		(property "Reference" "D15"
			(at 82.55 124.46 90)
			(effects
				(font
					(size 1.27 1.27)
					(thickness 0.15)
				)
				(justify left)
			)
		)
		(property "Value" "PTVS26VS1UR,115"
			(at 74.93 143.51 0)
			(effects
				(font
					(size 1.27 1.27)
					(thickness 0.15)
				)
				(justify left bottom)
				(hide yes)
			)
		)
		(property "Footprint" "antmicro-footprints:D_SOD-123"
			(at 72.39 143.51 0)
			(effects
				(font
					(size 1.27 1.27)
					(thickness 0.15)
				)
				(justify left bottom)
				(hide yes)
			)
		)
		(property "Datasheet" "https://www.mouser.com/datasheet/2/916/PTVSXS1UR_SER-1545507.pdf"
			(at 69.85 143.51 0)
			(effects
				(font
					(size 1.27 1.27)
					(thickness 0.15)
				)
				(justify left bottom)
				(hide yes)
			)
		)
		(property "Description" "Unidirectional TVS, 8 kV,  SOD-123F, 26 V, 400 W"
			(at 57.15 143.51 0)
			(effects
				(font
					(size 1.27 1.27)
				)
				(justify left bottom)
				(hide yes)
			)
		)
		(property "Author" "Antmicro"
			(at 62.23 143.51 0)
			(effects
				(font
					(size 1.27 1.27)
					(thickness 0.15)
				)
				(justify left bottom)
				(hide yes)
			)
		)
		(property "License" "Apache-2.0"
			(at 59.69 143.51 0)
			(effects
				(font
					(size 1.27 1.27)
					(thickness 0.15)
				)
				(justify left bottom)
				(hide yes)
			)
		)
		(property "Manufacturer" "Nexperia"
			(at 64.77 143.51 0)
			(effects
				(font
					(size 1.27 1.27)
				)
				(justify left bottom)
				(hide yes)
			)
		)
		(property "MPN" "PTVS26VS1UR,115"
			(at 82.55 126.9999 90)
			(effects
				(font
					(size 1.27 1.27)
				)
				(justify left)
			)
		)
		(pin "1"
		)
		(pin "2"
		)
		(instances
			(project "thunderbolt-to-10gbe-adapter"
				(path ""
					(reference "D15")
					(unit 1)
				)
			)
		)
	)
	(symbol
		(lib_id "antmicroResistors0402:R_0R_0402")
		(at 318.77 176.53 0)
		(unit 1)
		(exclude_from_sim no)
		(in_bom yes)
		(on_board yes)
		(dnp no)
		(property "Reference" "R236"
			(at 317.5 175.26 0)
			(effects
				(font
					(size 1.27 1.27)
					(thickness 0.15)
				)
			)
		)
		(property "Value" "R_0R_0402"
			(at 339.09 189.23 0)
			(effects
				(font
					(size 1.27 1.27)
					(thickness 0.15)
				)
				(justify left bottom)
				(hide yes)
			)
		)
		(property "Footprint" "antmicro-footprints:R_0402_1005Metric"
			(at 339.09 191.77 0)
			(effects
				(font
					(size 1.27 1.27)
					(thickness 0.15)
				)
				(justify left bottom)
				(hide yes)
			)
		)
		(property "Datasheet" "https://industrial.panasonic.com/cdbs/www-data/pdf/RDA0000/AOA0000C301.pdf"
			(at 339.09 194.31 0)
			(effects
				(font
					(size 1.27 1.27)
					(thickness 0.15)
				)
				(justify left bottom)
				(hide yes)
			)
		)
		(property "Description" "SMD Chip Resistor, Jumper, 0 ohm, 100 mW, 0402 [1005 Metric], Thick Film, General Purpose"
			(at 339.09 209.55 0)
			(effects
				(font
					(size 1.27 1.27)
				)
				(justify left bottom)
				(hide yes)
			)
		)
		(property "MPN" "ERJ2GE0R00X"
			(at 339.09 196.85 0)
			(effects
				(font
					(size 1.27 1.27)
					(thickness 0.15)
				)
				(justify left bottom)
				(hide yes)
			)
		)
		(property "Manufacturer" "Panasonic"
			(at 339.09 199.39 0)
			(effects
				(font
					(size 1.27 1.27)
					(thickness 0.15)
				)
				(justify left bottom)
				(hide yes)
			)
		)
		(property "License" "Apache-2.0"
			(at 339.09 201.93 0)
			(effects
				(font
					(size 1.27 1.27)
					(thickness 0.15)
				)
				(justify left bottom)
				(hide yes)
			)
		)
		(property "Author" "Antmicro"
			(at 339.09 204.47 0)
			(effects
				(font
					(size 1.27 1.27)
					(thickness 0.15)
				)
				(justify left bottom)
				(hide yes)
			)
		)
		(property "Val" "0R"
			(at 325.12 175.26 0)
			(effects
				(font
					(size 1.27 1.27)
					(thickness 0.15)
				)
			)
		)
		(property "Tolerance" "~"
			(at 339.09 186.69 0)
			(effects
				(font
					(size 1.27 1.27)
				)
				(justify left bottom)
				(hide yes)
			)
		)
		(property "Current" "1A"
			(at 339.09 207.01 0)
			(effects
				(font
					(size 1.27 1.27)
					(thickness 0.15)
				)
				(justify left bottom)
				(hide yes)
			)
		)
		(pin "2"
		)
		(pin "1"
		)
		(instances
			(project "thunderbolt-to-10gbe-adapter"
				(path ""
					(reference "R236")
					(unit 1)
				)
			)
		)
	)
	(symbol
		(lib_id "antmicropower:GND")
		(at 288.29 134.62 0)
		(unit 1)
		(exclude_from_sim no)
		(in_bom yes)
		(on_board yes)
		(dnp no)
		(property "Reference" "#PWR0488"
			(at 288.29 140.97 0)
			(effects
				(font
					(size 1.27 1.27)
				)
				(justify left bottom)
				(hide yes)
			)
		)
		(property "Value" "GND"
			(at 288.29 138.43 0)
			(effects
				(font
					(size 1.27 1.27)
					(thickness 0.15)
				)
			)
		)
		(property "Footprint" ""
			(at 297.18 142.24 0)
			(effects
				(font
					(size 1.27 1.27)
					(thickness 0.15)
				)
				(justify left bottom)
				(hide yes)
			)
		)
		(property "Datasheet" ""
			(at 297.18 147.32 0)
			(effects
				(font
					(size 1.27 1.27)
					(thickness 0.15)
				)
				(justify left bottom)
				(hide yes)
			)
		)
		(property "Description" ""
			(at 288.29 134.62 0)
			(effects
				(font
					(size 1.27 1.27)
				)
				(hide yes)
			)
		)
		(property "Author" "Antmicro"
			(at 297.18 142.24 0)
			(effects
				(font
					(size 1.27 1.27)
					(thickness 0.15)
				)
				(justify left bottom)
				(hide yes)
			)
		)
		(property "License" "Apache-2.0"
			(at 297.18 144.78 0)
			(effects
				(font
					(size 1.27 1.27)
					(thickness 0.15)
				)
				(justify left bottom)
				(hide yes)
			)
		)
		(pin "1"
		)
		(instances
			(project "thunderbolt-to-10gbe-adapter"
				(path ""
					(reference "#PWR0488")
					(unit 1)
				)
			)
		)
	)
	(symbol
		(lib_id "antmicroBarrelPowerConnectors:BarrelJack_Pin1.3mm_694103107102")
		(at 67.31 116.84 0)
		(unit 1)
		(exclude_from_sim no)
		(in_bom yes)
		(on_board yes)
		(dnp yes)
		(fields_autoplaced yes)
		(property "Reference" "J9"
			(at 59.69 110.49 0)
			(effects
				(font
					(size 1.27 1.27)
					(thickness 0.15)
				)
			)
		)
		(property "Value" "BarrelJack_Pin1.3mm_694103107102"
			(at 82.55 127 0)
			(effects
				(font
					(size 1.27 1.27)
					(thickness 0.15)
				)
				(justify left bottom)
				(hide yes)
			)
		)
		(property "Footprint" "antmicro-footprints:BarrelJack_Pin1.3mm_694103107102"
			(at 82.55 129.54 0)
			(effects
				(font
					(size 1.27 1.27)
					(thickness 0.15)
				)
				(justify left bottom)
				(hide yes)
			)
		)
		(property "Datasheet" "https://www.we-online.de/katalog/datasheet/694103107102.pdf"
			(at 82.55 132.08 0)
			(effects
				(font
					(size 1.27 1.27)
					(thickness 0.15)
				)
				(justify left bottom)
				(hide yes)
			)
		)
		(property "Description" "DC Power Connector, Jack, 5 A, 1.35 mm, PCB Mount, Surface Mount"
			(at 82.55 144.78 0)
			(effects
				(font
					(size 1.27 1.27)
					(thickness 0.15)
				)
				(justify left bottom)
				(hide yes)
			)
		)
		(property "MPN" "694103107102"
			(at 59.69 113.03 0)
			(effects
				(font
					(size 1.27 1.27)
					(thickness 0.15)
				)
			)
		)
		(property "Manufacturer" "Würth Elektronik"
			(at 82.55 137.16 0)
			(effects
				(font
					(size 1.27 1.27)
					(thickness 0.15)
				)
				(justify left bottom)
				(hide yes)
			)
		)
		(property "Author" "Antmicro"
			(at 82.55 139.7 0)
			(effects
				(font
					(size 1.27 1.27)
					(thickness 0.15)
				)
				(justify left bottom)
				(hide yes)
			)
		)
		(property "License" "Apache-2.0"
			(at 82.55 142.24 0)
			(effects
				(font
					(size 1.27 1.27)
					(thickness 0.15)
				)
				(justify left bottom)
				(hide yes)
			)
		)
		(pin "1"
		)
		(pin "2"
		)
		(pin "3"
		)
		(instances
			(project "thunderbolt-to-10gbe-adapter"
				(path ""
					(reference "J9")
					(unit 1)
				)
			)
		)
	)
	(symbol
		(lib_id "antmicroLEDIndicationDiscrete:LED_G_0603_LTST-C190GKT")
		(at 270.51 135.89 90)
		(unit 1)
		(exclude_from_sim no)
		(in_bom yes)
		(on_board yes)
		(dnp no)
		(property "Reference" "D16"
			(at 271.78 132.08 90)
			(effects
				(font
					(size 1.27 1.27)
				)
				(justify right)
			)
		)
		(property "Value" "LED_G_0603_LTST-C190GKT"
			(at 278.13 113.03 0)
			(effects
				(font
					(size 1.27 1.27)
					(thickness 0.15)
				)
				(justify left bottom)
				(hide yes)
			)
		)
		(property "Footprint" "antmicro-footprints:LED_0603_1608Metric_G"
			(at 280.67 113.03 0)
			(effects
				(font
					(size 1.27 1.27)
					(thickness 0.15)
				)
				(justify left bottom)
				(hide yes)
			)
		)
		(property "Datasheet" "https://media.digikey.com/pdf/Data%20Sheets/Lite-On%20PDFs/LTST-C190GKT.pdf"
			(at 283.21 113.03 0)
			(effects
				(font
					(size 1.27 1.27)
					(thickness 0.15)
				)
				(justify left bottom)
				(hide yes)
			)
		)
		(property "Description" "LED, Green, SMD, 0603, 20 mA, 2.1 V, 569 nm"
			(at 270.51 135.89 0)
			(effects
				(font
					(size 1.27 1.27)
				)
				(hide yes)
			)
		)
		(property "MPN" "LTST-C190GKT"
			(at 285.75 113.03 0)
			(effects
				(font
					(size 1.27 1.27)
					(thickness 0.15)
				)
				(justify left bottom)
				(hide yes)
			)
		)
		(property "Manufacturer" "Lite-On"
			(at 288.29 113.03 0)
			(effects
				(font
					(size 1.27 1.27)
					(thickness 0.15)
				)
				(justify left bottom)
				(hide yes)
			)
		)
		(property "Author" "Antmicro"
			(at 290.83 113.03 0)
			(effects
				(font
					(size 1.27 1.27)
					(thickness 0.15)
				)
				(justify left bottom)
				(hide yes)
			)
		)
		(property "License" "Apache-2.0"
			(at 293.37 113.03 0)
			(effects
				(font
					(size 1.27 1.27)
					(thickness 0.15)
				)
				(justify left bottom)
				(hide yes)
			)
		)
		(property "Color" "Green"
			(at 271.78 134.62 90)
			(effects
				(font
					(size 1.27 1.27)
				)
				(justify right)
			)
		)
		(pin "1"
		)
		(pin "2"
		)
		(instances
			(project "thunderbolt-to-10gbe-adapter"
				(path ""
					(reference "D16")
					(unit 1)
				)
			)
		)
	)
	(symbol
		(lib_id "antmicroTransistorsFETsMOSFETsSingle:SQS401EN-T1_BE3")
		(at 327.66 173.99 90)
		(unit 1)
		(exclude_from_sim no)
		(in_bom yes)
		(on_board yes)
		(dnp no)
		(property "Reference" "Q8"
			(at 325.12 161.29 90)
			(effects
				(font
					(size 1.27 1.27)
					(thickness 0.15)
				)
			)
		)
		(property "Value" "SQS401EN-T1_BE3"
			(at 337.82 158.75 0)
			(effects
				(font
					(size 1.27 1.27)
					(thickness 0.15)
				)
				(justify left bottom)
				(hide yes)
			)
		)
		(property "Footprint" "antmicro-footprints:Vishay_PowerPAK_1212-8_Single"
			(at 340.36 158.75 0)
			(effects
				(font
					(size 1.27 1.27)
					(thickness 0.15)
				)
				(justify left bottom)
				(hide yes)
			)
		)
		(property "Datasheet" "https://www.vishay.com/docs/65529/sqs401en.pdf"
			(at 342.9 158.75 0)
			(effects
				(font
					(size 1.27 1.27)
					(thickness 0.15)
				)
				(justify left bottom)
				(hide yes)
			)
		)
		(property "Description" "MOSFET, P Channel, 40 V, 16A, 0.047 ohm, PowerPAK 1212-8, Surface Mount"
			(at 327.66 173.99 0)
			(effects
				(font
					(size 1.27 1.27)
				)
				(hide yes)
			)
		)
		(property "MPN" "SQS401EN-T1_BE3"
			(at 325.12 163.83 90)
			(effects
				(font
					(size 1.27 1.27)
					(thickness 0.15)
				)
			)
		)
		(property "Manufacturer" "Vishay"
			(at 345.44 158.75 0)
			(effects
				(font
					(size 1.27 1.27)
					(thickness 0.15)
				)
				(justify left bottom)
				(hide yes)
			)
		)
		(property "Author" "Antmicro"
			(at 347.98 158.75 0)
			(effects
				(font
					(size 1.27 1.27)
					(thickness 0.15)
				)
				(justify left bottom)
				(hide yes)
			)
		)
		(property "License" "Apache-2.0"
			(at 350.52 158.75 0)
			(effects
				(font
					(size 1.27 1.27)
					(thickness 0.15)
				)
				(justify left bottom)
				(hide yes)
			)
		)
		(pin "4"
		)
		(pin "1"
		)
		(pin "3"
		)
		(pin "5"
		)
		(pin "2"
		)
		(instances
			(project "thunderbolt-to-10gbe-adapter"
				(path ""
					(reference "Q8")
					(unit 1)
				)
			)
		)
	)
	(symbol
		(lib_id "antmicroCapacitorsmisc:C_22u_100V_2220")
		(at 110.49 123.19 90)
		(unit 1)
		(exclude_from_sim no)
		(in_bom yes)
		(on_board yes)
		(dnp no)
		(property "Reference" "C311"
			(at 113.03 118.1036 90)
			(effects
				(font
					(size 1.27 1.27)
					(thickness 0.15)
				)
				(justify right)
			)
		)
		(property "Value" "C_22u_100V_2220"
			(at 120.65 102.87 0)
			(effects
				(font
					(size 1.27 1.27)
					(thickness 0.15)
				)
				(justify left bottom)
				(hide yes)
			)
		)
		(property "Footprint" "antmicro-footprints:C_2220_5650Metric"
			(at 123.19 102.87 0)
			(effects
				(font
					(size 1.27 1.27)
					(thickness 0.15)
				)
				(justify left bottom)
				(hide yes)
			)
		)
		(property "Datasheet" "https://product.tdk.com/en/search/capacitor/ceramic/mlcc/info?part_no=C5750X7S2A226M280KB"
			(at 125.73 102.87 0)
			(effects
				(font
					(size 1.27 1.27)
					(thickness 0.15)
				)
				(justify left bottom)
				(hide yes)
			)
		)
		(property "Description" "SMT Multilayer Ceramic Capacitor, 22 µF, 100 V, 2220 [5750 Metric], ± 20%, X7S, C"
			(at 143.51 102.87 0)
			(effects
				(font
					(size 1.27 1.27)
				)
				(justify left bottom)
				(hide yes)
			)
		)
		(property "MPN" "C5750X7S2A226M280KB"
			(at 128.27 102.87 0)
			(effects
				(font
					(size 1.27 1.27)
					(thickness 0.15)
				)
				(justify left bottom)
				(hide yes)
			)
		)
		(property "Manufacturer" "TDK"
			(at 130.81 102.87 0)
			(effects
				(font
					(size 1.27 1.27)
					(thickness 0.15)
				)
				(justify left bottom)
				(hide yes)
			)
		)
		(property "License" "Apache-2.0"
			(at 133.35 102.87 0)
			(effects
				(font
					(size 1.27 1.27)
					(thickness 0.15)
				)
				(justify left bottom)
				(hide yes)
			)
		)
		(property "Author" "Antmicro"
			(at 135.89 102.87 0)
			(effects
				(font
					(size 1.27 1.27)
					(thickness 0.15)
				)
				(justify left bottom)
				(hide yes)
			)
		)
		(property "Val" "22u"
			(at 113.03 120.6436 90)
			(effects
				(font
					(size 1.27 1.27)
					(thickness 0.15)
				)
				(justify right)
			)
		)
		(property "Voltage" "100V"
			(at 113.03 123.1835 90)
			(effects
				(font
					(size 1.27 1.27)
				)
				(justify right)
			)
		)
		(property "Dielectric" "X7S"
			(at 140.97 102.87 0)
			(effects
				(font
					(size 1.27 1.27)
				)
				(justify left bottom)
				(hide yes)
			)
		)
		(property "Public" "False"
			(at 143.51 102.87 0)
			(effects
				(font
					(size 1.27 1.27)
				)
				(justify left bottom)
				(hide yes)
			)
		)
		(pin "1"
		)
		(pin "2"
		)
		(instances
			(project "thunderbolt-to-10gbe-adapter"
				(path ""
					(reference "C311")
					(unit 1)
				)
			)
		)
	)
	(symbol
		(lib_id "antmicropower:+5V")
		(at 346.71 119.38 0)
		(unit 1)
		(exclude_from_sim no)
		(in_bom yes)
		(on_board yes)
		(dnp no)
		(property "Reference" "#PWR0495"
			(at 361.95 121.92 0)
			(effects
				(font
					(size 1.27 1.27)
					(thickness 0.15)
				)
				(justify left bottom)
				(hide yes)
			)
		)
		(property "Value" "+5V"
			(at 346.71 115.57 0)
			(effects
				(font
					(size 1.27 1.27)
					(thickness 0.15)
				)
			)
		)
		(property "Footprint" ""
			(at 361.95 127 0)
			(effects
				(font
					(size 1.27 1.27)
					(thickness 0.15)
				)
				(justify left bottom)
				(hide yes)
			)
		)
		(property "Datasheet" ""
			(at 361.95 129.54 0)
			(effects
				(font
					(size 1.27 1.27)
					(thickness 0.15)
				)
				(justify left bottom)
				(hide yes)
			)
		)
		(property "Description" ""
			(at 361.95 132.08 0)
			(effects
				(font
					(size 1.27 1.27)
				)
				(justify left bottom)
				(hide yes)
			)
		)
		(property "Author" "Antmicro"
			(at 361.95 127 0)
			(effects
				(font
					(size 1.27 1.27)
					(thickness 0.15)
				)
				(justify left bottom)
				(hide yes)
			)
		)
		(property "License" "Apache-2.0"
			(at 361.95 129.54 0)
			(effects
				(font
					(size 1.27 1.27)
					(thickness 0.15)
				)
				(justify left bottom)
				(hide yes)
			)
		)
		(pin "1"
		)
		(instances
			(project "thunderbolt-to-10gbe-adapter"
				(path ""
					(reference "#PWR0495")
					(unit 1)
				)
			)
		)
	)
	(symbol
		(lib_id "antmicroCapacitorsmisc:C_22u_25V_0805")
		(at 245.11 129.54 90)
		(unit 1)
		(exclude_from_sim no)
		(in_bom yes)
		(on_board yes)
		(dnp no)
		(property "Reference" "C319"
			(at 246.888 124.4601 90)
			(effects
				(font
					(size 1.27 1.27)
					(thickness 0.15)
				)
				(justify right)
			)
		)
		(property "Value" "C_22u_25V_0805"
			(at 255.27 109.22 0)
			(effects
				(font
					(size 1.27 1.27)
					(thickness 0.15)
				)
				(justify left bottom)
				(hide yes)
			)
		)
		(property "Footprint" "antmicro-footprints:C_0805_2012Metric"
			(at 257.81 109.22 0)
			(effects
				(font
					(size 1.27 1.27)
					(thickness 0.15)
				)
				(justify left bottom)
				(hide yes)
			)
		)
		(property "Datasheet" "https://product.samsungsem.com/mlcc/CL21A226MAYNNN.do"
			(at 260.35 109.22 0)
			(effects
				(font
					(size 1.27 1.27)
					(thickness 0.15)
				)
				(justify left bottom)
				(hide yes)
			)
		)
		(property "Description" "SMT Multilayer Ceramic Capacitor, 22uF, +/-20%, 25V, X5R, 0805 [2012 Metric]"
			(at 278.13 109.22 0)
			(effects
				(font
					(size 1.27 1.27)
				)
				(justify left bottom)
				(hide yes)
			)
		)
		(property "MPN" "CL21A226MAYNNNE"
			(at 262.89 109.22 0)
			(effects
				(font
					(size 1.27 1.27)
					(thickness 0.15)
				)
				(justify left bottom)
				(hide yes)
			)
		)
		(property "Manufacturer" "Samsung Electro-Mechanics"
			(at 265.43 109.22 0)
			(effects
				(font
					(size 1.27 1.27)
					(thickness 0.15)
				)
				(justify left bottom)
				(hide yes)
			)
		)
		(property "License" "Apache-2.0"
			(at 267.97 109.22 0)
			(effects
				(font
					(size 1.27 1.27)
					(thickness 0.15)
				)
				(justify left bottom)
				(hide yes)
			)
		)
		(property "Author" "Antmicro"
			(at 270.51 109.22 0)
			(effects
				(font
					(size 1.27 1.27)
					(thickness 0.15)
				)
				(justify left bottom)
				(hide yes)
			)
		)
		(property "Val" "22u"
			(at 246.888 127.0001 90)
			(effects
				(font
					(size 1.27 1.27)
					(thickness 0.15)
				)
				(justify right)
			)
		)
		(property "Voltage" "25V"
			(at 246.888 129.54 90)
			(effects
				(font
					(size 1.27 1.27)
				)
				(justify right)
			)
		)
		(property "Dielectric" "X5R"
			(at 275.59 109.22 0)
			(effects
				(font
					(size 1.27 1.27)
				)
				(justify left bottom)
				(hide yes)
			)
		)
		(property "Public" "False"
			(at 278.13 109.22 0)
			(effects
				(font
					(size 1.27 1.27)
				)
				(justify left bottom)
				(hide yes)
			)
		)
		(pin "2"
		)
		(pin "1"
		)
		(instances
			(project "thunderbolt-to-10gbe-adapter"
				(path ""
					(reference "C319")
					(unit 1)
				)
			)
		)
	)
	(symbol
		(lib_id "antmicropower:GND")
		(at 149.86 142.24 0)
		(unit 1)
		(exclude_from_sim no)
		(in_bom yes)
		(on_board yes)
		(dnp no)
		(property "Reference" "#PWR0478"
			(at 149.86 148.59 0)
			(effects
				(font
					(size 1.27 1.27)
				)
				(justify left bottom)
				(hide yes)
			)
		)
		(property "Value" "GND"
			(at 149.86 146.05 0)
			(effects
				(font
					(size 1.27 1.27)
					(thickness 0.15)
				)
			)
		)
		(property "Footprint" ""
			(at 158.75 149.86 0)
			(effects
				(font
					(size 1.27 1.27)
					(thickness 0.15)
				)
				(justify left bottom)
				(hide yes)
			)
		)
		(property "Datasheet" ""
			(at 158.75 154.94 0)
			(effects
				(font
					(size 1.27 1.27)
					(thickness 0.15)
				)
				(justify left bottom)
				(hide yes)
			)
		)
		(property "Description" ""
			(at 149.86 142.24 0)
			(effects
				(font
					(size 1.27 1.27)
				)
				(hide yes)
			)
		)
		(property "Author" "Antmicro"
			(at 158.75 149.86 0)
			(effects
				(font
					(size 1.27 1.27)
					(thickness 0.15)
				)
				(justify left bottom)
				(hide yes)
			)
		)
		(property "License" "Apache-2.0"
			(at 158.75 152.4 0)
			(effects
				(font
					(size 1.27 1.27)
					(thickness 0.15)
				)
				(justify left bottom)
				(hide yes)
			)
		)
		(pin "1"
		)
		(instances
			(project "thunderbolt-to-10gbe-adapter"
				(path ""
					(reference "#PWR0478")
					(unit 1)
				)
			)
		)
	)
	(symbol
		(lib_id "antmicropower:GND")
		(at 252.73 130.81 0)
		(unit 1)
		(exclude_from_sim no)
		(in_bom yes)
		(on_board yes)
		(dnp no)
		(property "Reference" "#PWR0485"
			(at 252.73 137.16 0)
			(effects
				(font
					(size 1.27 1.27)
				)
				(justify left bottom)
				(hide yes)
			)
		)
		(property "Value" "GND"
			(at 252.73 134.62 0)
			(effects
				(font
					(size 1.27 1.27)
					(thickness 0.15)
				)
			)
		)
		(property "Footprint" ""
			(at 261.62 138.43 0)
			(effects
				(font
					(size 1.27 1.27)
					(thickness 0.15)
				)
				(justify left bottom)
				(hide yes)
			)
		)
		(property "Datasheet" ""
			(at 261.62 143.51 0)
			(effects
				(font
					(size 1.27 1.27)
					(thickness 0.15)
				)
				(justify left bottom)
				(hide yes)
			)
		)
		(property "Description" ""
			(at 252.73 130.81 0)
			(effects
				(font
					(size 1.27 1.27)
				)
				(hide yes)
			)
		)
		(property "Author" "Antmicro"
			(at 261.62 138.43 0)
			(effects
				(font
					(size 1.27 1.27)
					(thickness 0.15)
				)
				(justify left bottom)
				(hide yes)
			)
		)
		(property "License" "Apache-2.0"
			(at 261.62 140.97 0)
			(effects
				(font
					(size 1.27 1.27)
					(thickness 0.15)
				)
				(justify left bottom)
				(hide yes)
			)
		)
		(pin "1"
		)
		(instances
			(project "thunderbolt-to-10gbe-adapter"
				(path ""
					(reference "#PWR0485")
					(unit 1)
				)
			)
		)
	)
	(symbol
		(lib_id "antmicroCapacitors0402:C_100n_0402")
		(at 111.76 142.24 90)
		(unit 1)
		(exclude_from_sim no)
		(in_bom yes)
		(on_board yes)
		(dnp no)
		(fields_autoplaced yes)
		(property "Reference" "C312"
			(at 113.538 138.43 90)
			(effects
				(font
					(size 1.27 1.27)
					(thickness 0.15)
				)
				(justify right)
			)
		)
		(property "Value" "C_100n_0402"
			(at 121.92 121.92 0)
			(effects
				(font
					(size 1.27 1.27)
					(thickness 0.15)
				)
				(justify left bottom)
				(hide yes)
			)
		)
		(property "Footprint" "antmicro-footprints:C_0402_1005Metric"
			(at 124.46 121.92 0)
			(effects
				(font
					(size 1.27 1.27)
					(thickness 0.15)
				)
				(justify left bottom)
				(hide yes)
			)
		)
		(property "Datasheet" "https://www.murata.com/products/productdetail?partno=GRM155R61H104KE14%23"
			(at 127 121.92 0)
			(effects
				(font
					(size 1.27 1.27)
					(thickness 0.15)
				)
				(justify left bottom)
				(hide yes)
			)
		)
		(property "Description" "SMD Multilayer Ceramic Capacitor, 0.1 µF, 50 V, 0402 [1005 Metric], ± 10%, X5R, GRM Series"
			(at 144.78 121.92 0)
			(effects
				(font
					(size 1.27 1.27)
				)
				(justify left bottom)
				(hide yes)
			)
		)
		(property "MPN" "GRM155R61H104KE14D"
			(at 129.54 121.92 0)
			(effects
				(font
					(size 1.27 1.27)
					(thickness 0.15)
				)
				(justify left bottom)
				(hide yes)
			)
		)
		(property "Manufacturer" "Murata"
			(at 132.08 121.92 0)
			(effects
				(font
					(size 1.27 1.27)
					(thickness 0.15)
				)
				(justify left bottom)
				(hide yes)
			)
		)
		(property "License" "Apache-2.0"
			(at 134.62 121.92 0)
			(effects
				(font
					(size 1.27 1.27)
					(thickness 0.15)
				)
				(justify left bottom)
				(hide yes)
			)
		)
		(property "Author" "Antmicro"
			(at 137.16 121.92 0)
			(effects
				(font
					(size 1.27 1.27)
					(thickness 0.15)
				)
				(justify left bottom)
				(hide yes)
			)
		)
		(property "Val" "100n"
			(at 113.792 140.716 90)
			(effects
				(font
					(size 1.27 1.27)
					(thickness 0.15)
				)
				(justify right)
			)
		)
		(property "Voltage" "50V"
			(at 139.7 121.92 0)
			(effects
				(font
					(size 1.27 1.27)
				)
				(justify left bottom)
				(hide yes)
			)
		)
		(property "Dielectric" "X5R"
			(at 142.24 121.92 0)
			(effects
				(font
					(size 1.27 1.27)
				)
				(justify left bottom)
				(hide yes)
			)
		)
		(pin "1"
		)
		(pin "2"
		)
		(instances
			(project "thunderbolt-to-10gbe-adapter"
				(path ""
					(reference "C312")
					(unit 1)
				)
			)
		)
	)
	(symbol
		(lib_id "antmicropower:GND")
		(at 260.35 130.81 0)
		(unit 1)
		(exclude_from_sim no)
		(in_bom yes)
		(on_board yes)
		(dnp no)
		(property "Reference" "#PWR0486"
			(at 260.35 137.16 0)
			(effects
				(font
					(size 1.27 1.27)
				)
				(justify left bottom)
				(hide yes)
			)
		)
		(property "Value" "GND"
			(at 260.35 134.62 0)
			(effects
				(font
					(size 1.27 1.27)
					(thickness 0.15)
				)
			)
		)
		(property "Footprint" ""
			(at 269.24 138.43 0)
			(effects
				(font
					(size 1.27 1.27)
					(thickness 0.15)
				)
				(justify left bottom)
				(hide yes)
			)
		)
		(property "Datasheet" ""
			(at 269.24 143.51 0)
			(effects
				(font
					(size 1.27 1.27)
					(thickness 0.15)
				)
				(justify left bottom)
				(hide yes)
			)
		)
		(property "Description" ""
			(at 260.35 130.81 0)
			(effects
				(font
					(size 1.27 1.27)
				)
				(hide yes)
			)
		)
		(property "Author" "Antmicro"
			(at 269.24 138.43 0)
			(effects
				(font
					(size 1.27 1.27)
					(thickness 0.15)
				)
				(justify left bottom)
				(hide yes)
			)
		)
		(property "License" "Apache-2.0"
			(at 269.24 140.97 0)
			(effects
				(font
					(size 1.27 1.27)
					(thickness 0.15)
				)
				(justify left bottom)
				(hide yes)
			)
		)
		(pin "1"
		)
		(instances
			(project "thunderbolt-to-10gbe-adapter"
				(path ""
					(reference "#PWR0486")
					(unit 1)
				)
			)
		)
	)
	(symbol
		(lib_id "antmicroCapacitorsmisc:C_22u_25V_0805")
		(at 237.49 129.54 90)
		(unit 1)
		(exclude_from_sim no)
		(in_bom yes)
		(on_board yes)
		(dnp no)
		(property "Reference" "C318"
			(at 239.268 124.4601 90)
			(effects
				(font
					(size 1.27 1.27)
					(thickness 0.15)
				)
				(justify right)
			)
		)
		(property "Value" "C_22u_25V_0805"
			(at 247.65 109.22 0)
			(effects
				(font
					(size 1.27 1.27)
					(thickness 0.15)
				)
				(justify left bottom)
				(hide yes)
			)
		)
		(property "Footprint" "antmicro-footprints:C_0805_2012Metric"
			(at 250.19 109.22 0)
			(effects
				(font
					(size 1.27 1.27)
					(thickness 0.15)
				)
				(justify left bottom)
				(hide yes)
			)
		)
		(property "Datasheet" "https://product.samsungsem.com/mlcc/CL21A226MAYNNN.do"
			(at 252.73 109.22 0)
			(effects
				(font
					(size 1.27 1.27)
					(thickness 0.15)
				)
				(justify left bottom)
				(hide yes)
			)
		)
		(property "Description" "SMT Multilayer Ceramic Capacitor, 22uF, +/-20%, 25V, X5R, 0805 [2012 Metric]"
			(at 270.51 109.22 0)
			(effects
				(font
					(size 1.27 1.27)
				)
				(justify left bottom)
				(hide yes)
			)
		)
		(property "MPN" "CL21A226MAYNNNE"
			(at 255.27 109.22 0)
			(effects
				(font
					(size 1.27 1.27)
					(thickness 0.15)
				)
				(justify left bottom)
				(hide yes)
			)
		)
		(property "Manufacturer" "Samsung Electro-Mechanics"
			(at 257.81 109.22 0)
			(effects
				(font
					(size 1.27 1.27)
					(thickness 0.15)
				)
				(justify left bottom)
				(hide yes)
			)
		)
		(property "License" "Apache-2.0"
			(at 260.35 109.22 0)
			(effects
				(font
					(size 1.27 1.27)
					(thickness 0.15)
				)
				(justify left bottom)
				(hide yes)
			)
		)
		(property "Author" "Antmicro"
			(at 262.89 109.22 0)
			(effects
				(font
					(size 1.27 1.27)
					(thickness 0.15)
				)
				(justify left bottom)
				(hide yes)
			)
		)
		(property "Val" "22u"
			(at 239.268 127.0001 90)
			(effects
				(font
					(size 1.27 1.27)
					(thickness 0.15)
				)
				(justify right)
			)
		)
		(property "Voltage" "25V"
			(at 239.268 129.54 90)
			(effects
				(font
					(size 1.27 1.27)
				)
				(justify right)
			)
		)
		(property "Dielectric" "X5R"
			(at 267.97 109.22 0)
			(effects
				(font
					(size 1.27 1.27)
				)
				(justify left bottom)
				(hide yes)
			)
		)
		(property "Public" "False"
			(at 270.51 109.22 0)
			(effects
				(font
					(size 1.27 1.27)
				)
				(justify left bottom)
				(hide yes)
			)
		)
		(pin "2"
		)
		(pin "1"
		)
		(instances
			(project "thunderbolt-to-10gbe-adapter"
				(path ""
					(reference "C318")
					(unit 1)
				)
			)
		)
	)
	(symbol
		(lib_id "antmicroCapacitors0402:C_100n_0402")
		(at 295.91 142.24 90)
		(unit 1)
		(exclude_from_sim no)
		(in_bom yes)
		(on_board yes)
		(dnp no)
		(property "Reference" "C322"
			(at 297.688 138.43 90)
			(effects
				(font
					(size 1.27 1.27)
					(thickness 0.15)
				)
				(justify right)
			)
		)
		(property "Value" "C_100n_0402"
			(at 306.07 121.92 0)
			(effects
				(font
					(size 1.27 1.27)
					(thickness 0.15)
				)
				(justify left bottom)
				(hide yes)
			)
		)
		(property "Footprint" "antmicro-footprints:C_0402_1005Metric"
			(at 308.61 121.92 0)
			(effects
				(font
					(size 1.27 1.27)
					(thickness 0.15)
				)
				(justify left bottom)
				(hide yes)
			)
		)
		(property "Datasheet" "https://www.murata.com/products/productdetail?partno=GRM155R61H104KE14%23"
			(at 311.15 121.92 0)
			(effects
				(font
					(size 1.27 1.27)
					(thickness 0.15)
				)
				(justify left bottom)
				(hide yes)
			)
		)
		(property "Description" "SMD Multilayer Ceramic Capacitor, 0.1 µF, 50 V, 0402 [1005 Metric], ± 10%, X5R, GRM Series"
			(at 295.91 142.24 0)
			(effects
				(font
					(size 1.27 1.27)
				)
				(hide yes)
			)
		)
		(property "MPN" "GRM155R61H104KE14D"
			(at 313.69 121.92 0)
			(effects
				(font
					(size 1.27 1.27)
					(thickness 0.15)
				)
				(justify left bottom)
				(hide yes)
			)
		)
		(property "Manufacturer" "Murata"
			(at 316.23 121.92 0)
			(effects
				(font
					(size 1.27 1.27)
					(thickness 0.15)
				)
				(justify left bottom)
				(hide yes)
			)
		)
		(property "License" "Apache-2.0"
			(at 318.77 121.92 0)
			(effects
				(font
					(size 1.27 1.27)
					(thickness 0.15)
				)
				(justify left bottom)
				(hide yes)
			)
		)
		(property "Author" "Antmicro"
			(at 321.31 121.92 0)
			(effects
				(font
					(size 1.27 1.27)
					(thickness 0.15)
				)
				(justify left bottom)
				(hide yes)
			)
		)
		(property "Val" "100n"
			(at 297.688 140.97 90)
			(effects
				(font
					(size 1.27 1.27)
					(thickness 0.15)
				)
				(justify right)
			)
		)
		(property "Voltage" "50V"
			(at 323.85 121.92 0)
			(effects
				(font
					(size 1.27 1.27)
				)
				(justify left bottom)
				(hide yes)
			)
		)
		(property "Dielectric" "X5R"
			(at 326.39 121.92 0)
			(effects
				(font
					(size 1.27 1.27)
				)
				(justify left bottom)
				(hide yes)
			)
		)
		(pin "2"
		)
		(pin "1"
		)
		(instances
			(project "thunderbolt-to-10gbe-adapter"
				(path ""
					(reference "C322")
					(unit 1)
				)
			)
		)
	)
	(symbol
		(lib_id "antmicropower:GND")
		(at 158.75 142.24 0)
		(unit 1)
		(exclude_from_sim no)
		(in_bom yes)
		(on_board yes)
		(dnp no)
		(property "Reference" "#PWR0479"
			(at 158.75 148.59 0)
			(effects
				(font
					(size 1.27 1.27)
				)
				(justify left bottom)
				(hide yes)
			)
		)
		(property "Value" "GND"
			(at 158.75 146.05 0)
			(effects
				(font
					(size 1.27 1.27)
					(thickness 0.15)
				)
			)
		)
		(property "Footprint" ""
			(at 167.64 149.86 0)
			(effects
				(font
					(size 1.27 1.27)
					(thickness 0.15)
				)
				(justify left bottom)
				(hide yes)
			)
		)
		(property "Datasheet" ""
			(at 167.64 154.94 0)
			(effects
				(font
					(size 1.27 1.27)
					(thickness 0.15)
				)
				(justify left bottom)
				(hide yes)
			)
		)
		(property "Description" ""
			(at 158.75 142.24 0)
			(effects
				(font
					(size 1.27 1.27)
				)
				(hide yes)
			)
		)
		(property "Author" "Antmicro"
			(at 167.64 149.86 0)
			(effects
				(font
					(size 1.27 1.27)
					(thickness 0.15)
				)
				(justify left bottom)
				(hide yes)
			)
		)
		(property "License" "Apache-2.0"
			(at 167.64 152.4 0)
			(effects
				(font
					(size 1.27 1.27)
					(thickness 0.15)
				)
				(justify left bottom)
				(hide yes)
			)
		)
		(pin "1"
		)
		(instances
			(project "thunderbolt-to-10gbe-adapter"
				(path ""
					(reference "#PWR0479")
					(unit 1)
				)
			)
		)
	)
	(symbol
		(lib_id "antmicropower:GND")
		(at 142.24 142.24 0)
		(unit 1)
		(exclude_from_sim no)
		(in_bom yes)
		(on_board yes)
		(dnp no)
		(property "Reference" "#PWR0477"
			(at 142.24 148.59 0)
			(effects
				(font
					(size 1.27 1.27)
				)
				(justify left bottom)
				(hide yes)
			)
		)
		(property "Value" "GND"
			(at 142.24 146.05 0)
			(effects
				(font
					(size 1.27 1.27)
					(thickness 0.15)
				)
			)
		)
		(property "Footprint" ""
			(at 151.13 149.86 0)
			(effects
				(font
					(size 1.27 1.27)
					(thickness 0.15)
				)
				(justify left bottom)
				(hide yes)
			)
		)
		(property "Datasheet" ""
			(at 151.13 154.94 0)
			(effects
				(font
					(size 1.27 1.27)
					(thickness 0.15)
				)
				(justify left bottom)
				(hide yes)
			)
		)
		(property "Description" ""
			(at 142.24 142.24 0)
			(effects
				(font
					(size 1.27 1.27)
				)
				(hide yes)
			)
		)
		(property "Author" "Antmicro"
			(at 151.13 149.86 0)
			(effects
				(font
					(size 1.27 1.27)
					(thickness 0.15)
				)
				(justify left bottom)
				(hide yes)
			)
		)
		(property "License" "Apache-2.0"
			(at 151.13 152.4 0)
			(effects
				(font
					(size 1.27 1.27)
					(thickness 0.15)
				)
				(justify left bottom)
				(hide yes)
			)
		)
		(pin "1"
		)
		(instances
			(project "thunderbolt-to-10gbe-adapter"
				(path ""
					(reference "#PWR0477")
					(unit 1)
				)
			)
		)
	)
	(symbol
		(lib_id "antmicropower:GND")
		(at 130.81 124.46 0)
		(unit 1)
		(exclude_from_sim no)
		(in_bom yes)
		(on_board yes)
		(dnp no)
		(property "Reference" "#PWR0476"
			(at 130.81 130.81 0)
			(effects
				(font
					(size 1.27 1.27)
				)
				(justify left bottom)
				(hide yes)
			)
		)
		(property "Value" "GND"
			(at 130.81 128.27 0)
			(effects
				(font
					(size 1.27 1.27)
					(thickness 0.15)
				)
			)
		)
		(property "Footprint" ""
			(at 139.7 132.08 0)
			(effects
				(font
					(size 1.27 1.27)
					(thickness 0.15)
				)
				(justify left bottom)
				(hide yes)
			)
		)
		(property "Datasheet" ""
			(at 139.7 137.16 0)
			(effects
				(font
					(size 1.27 1.27)
					(thickness 0.15)
				)
				(justify left bottom)
				(hide yes)
			)
		)
		(property "Description" ""
			(at 130.81 124.46 0)
			(effects
				(font
					(size 1.27 1.27)
				)
				(hide yes)
			)
		)
		(property "Author" "Antmicro"
			(at 139.7 132.08 0)
			(effects
				(font
					(size 1.27 1.27)
					(thickness 0.15)
				)
				(justify left bottom)
				(hide yes)
			)
		)
		(property "License" "Apache-2.0"
			(at 139.7 134.62 0)
			(effects
				(font
					(size 1.27 1.27)
					(thickness 0.15)
				)
				(justify left bottom)
				(hide yes)
			)
		)
		(pin "1"
		)
		(instances
			(project "thunderbolt-to-10gbe-adapter"
				(path ""
					(reference "#PWR0476")
					(unit 1)
				)
			)
		)
	)
	(symbol
		(lib_id "antmicropower:PWR_FLAG")
		(at 304.8 120.65 0)
		(unit 1)
		(exclude_from_sim no)
		(in_bom yes)
		(on_board yes)
		(dnp no)
		(property "Reference" "#FLG037"
			(at 304.8 118.745 0)
			(effects
				(font
					(size 1.27 1.27)
				)
				(hide yes)
			)
		)
		(property "Value" "PWR_FLAG"
			(at 304.8 116.84 0)
			(effects
				(font
					(size 1.27 1.27)
				)
			)
		)
		(property "Footprint" ""
			(at 304.8 120.65 0)
			(effects
				(font
					(size 1.27 1.27)
				)
				(hide yes)
			)
		)
		(property "Datasheet" ""
			(at 304.8 120.65 0)
			(effects
				(font
					(size 1.27 1.27)
				)
				(hide yes)
			)
		)
		(property "Description" ""
			(at 304.8 123.19 0)
			(effects
				(font
					(size 1.27 1.27)
				)
				(justify left bottom)
				(hide yes)
			)
		)
		(pin "1"
		)
		(instances
			(project "thunderbolt-to-10gbe-adapter"
				(path ""
					(reference "#FLG037")
					(unit 1)
				)
			)
		)
	)
	(symbol
		(lib_id "antmicroTestPoints:TP_0.75mm_SMD")
		(at 332.74 195.58 0)
		(unit 1)
		(exclude_from_sim no)
		(in_bom no)
		(on_board yes)
		(dnp no)
		(fields_autoplaced yes)
		(property "Reference" "TP37"
			(at 337.82 195.58 0)
			(effects
				(font
					(size 1.27 1.27)
					(thickness 0.15)
				)
				(justify left)
			)
		)
		(property "Value" "TP_0.75mm_SMD"
			(at 342.9 199.39 0)
			(effects
				(font
					(size 1.27 1.27)
					(thickness 0.15)
				)
				(justify left bottom)
				(hide yes)
			)
		)
		(property "Footprint" "antmicro-footprints:TP_SMD_0.75mm"
			(at 342.9 201.93 0)
			(effects
				(font
					(size 1.27 1.27)
					(thickness 0.15)
				)
				(justify left bottom)
				(hide yes)
			)
		)
		(property "Datasheet" ""
			(at 350.52 208.28 0)
			(effects
				(font
					(size 1.27 1.27)
					(thickness 0.15)
				)
				(justify left bottom)
				(hide yes)
			)
		)
		(property "Description" "SMT test point"
			(at 343.535 209.55 0)
			(effects
				(font
					(size 1.27 1.27)
				)
				(justify left bottom)
				(hide yes)
			)
		)
		(property "MPN" ""
			(at 343.535 207.01 0)
			(effects
				(font
					(size 1.27 1.27)
					(thickness 0.15)
				)
				(justify left bottom)
				(hide yes)
			)
		)
		(property "Manufacturer" ""
			(at 343.535 201.93 0)
			(effects
				(font
					(size 1.27 1.27)
					(thickness 0.15)
				)
				(justify left bottom)
				(hide yes)
			)
		)
		(property "Author" "Antmicro"
			(at 342.9 204.47 0)
			(effects
				(font
					(size 1.27 1.27)
					(thickness 0.15)
				)
				(justify left bottom)
				(hide yes)
			)
		)
		(property "License" "Apache-2.0"
			(at 342.9 207.01 0)
			(effects
				(font
					(size 1.27 1.27)
					(thickness 0.15)
				)
				(justify left bottom)
				(hide yes)
			)
		)
		(pin "1"
		)
		(instances
			(project "thunderbolt-to-10gbe-adapter"
				(path ""
					(reference "TP37")
					(unit 1)
				)
			)
		)
	)
	(symbol
		(lib_id "antmicroCapacitors0402:C_100n_0402")
		(at 130.81 123.19 90)
		(unit 1)
		(exclude_from_sim no)
		(in_bom yes)
		(on_board yes)
		(dnp no)
		(fields_autoplaced yes)
		(property "Reference" "C314"
			(at 133.35 119.3736 90)
			(effects
				(font
					(size 1.27 1.27)
					(thickness 0.15)
				)
				(justify right)
			)
		)
		(property "Value" "C_100n_0402"
			(at 140.97 102.87 0)
			(effects
				(font
					(size 1.27 1.27)
					(thickness 0.15)
				)
				(justify left bottom)
				(hide yes)
			)
		)
		(property "Footprint" "antmicro-footprints:C_0402_1005Metric"
			(at 143.51 102.87 0)
			(effects
				(font
					(size 1.27 1.27)
					(thickness 0.15)
				)
				(justify left bottom)
				(hide yes)
			)
		)
		(property "Datasheet" "https://www.murata.com/products/productdetail?partno=GRM155R61H104KE14%23"
			(at 146.05 102.87 0)
			(effects
				(font
					(size 1.27 1.27)
					(thickness 0.15)
				)
				(justify left bottom)
				(hide yes)
			)
		)
		(property "Description" "SMD Multilayer Ceramic Capacitor, 0.1 µF, 50 V, 0402 [1005 Metric], ± 10%, X5R, GRM Series"
			(at 163.83 102.87 0)
			(effects
				(font
					(size 1.27 1.27)
				)
				(justify left bottom)
				(hide yes)
			)
		)
		(property "MPN" "GRM155R61H104KE14D"
			(at 148.59 102.87 0)
			(effects
				(font
					(size 1.27 1.27)
					(thickness 0.15)
				)
				(justify left bottom)
				(hide yes)
			)
		)
		(property "Manufacturer" "Murata"
			(at 151.13 102.87 0)
			(effects
				(font
					(size 1.27 1.27)
					(thickness 0.15)
				)
				(justify left bottom)
				(hide yes)
			)
		)
		(property "License" "Apache-2.0"
			(at 153.67 102.87 0)
			(effects
				(font
					(size 1.27 1.27)
					(thickness 0.15)
				)
				(justify left bottom)
				(hide yes)
			)
		)
		(property "Author" "Antmicro"
			(at 156.21 102.87 0)
			(effects
				(font
					(size 1.27 1.27)
					(thickness 0.15)
				)
				(justify left bottom)
				(hide yes)
			)
		)
		(property "Val" "100n"
			(at 133.35 121.9136 90)
			(effects
				(font
					(size 1.27 1.27)
					(thickness 0.15)
				)
				(justify right)
			)
		)
		(property "Voltage" "50V"
			(at 158.75 102.87 0)
			(effects
				(font
					(size 1.27 1.27)
				)
				(justify left bottom)
				(hide yes)
			)
		)
		(property "Dielectric" "X5R"
			(at 161.29 102.87 0)
			(effects
				(font
					(size 1.27 1.27)
				)
				(justify left bottom)
				(hide yes)
			)
		)
		(pin "2"
		)
		(pin "1"
		)
		(instances
			(project "thunderbolt-to-10gbe-adapter"
				(path ""
					(reference "C314")
					(unit 1)
				)
			)
		)
	)
)
